G04*
G04 #@! TF.GenerationSoftware,Altium Limited,Altium Designer,23.7.1 (13)*
G04*
G04 Layer_Color=39423*
%FSLAX25Y25*%
%MOIN*%
G70*
G04*
G04 #@! TF.SameCoordinates,AF00DCEB-AC48-4C7C-91EA-99F42E284231*
G04*
G04*
G04 #@! TF.FilePolarity,Positive*
G04*
G01*
G75*
%ADD15C,0.00787*%
%ADD16C,0.00500*%
%ADD20C,0.00300*%
%ADD21C,0.00100*%
%ADD23C,0.00394*%
G36*
X289314Y-273032D02*
X289262Y-273106D01*
X289214Y-273172D01*
X289165Y-273228D01*
X289125Y-273280D01*
X289088Y-273317D01*
X289058Y-273346D01*
X289040Y-273365D01*
X289032Y-273372D01*
X289003Y-273394D01*
X288969Y-273420D01*
X288903Y-273461D01*
X288873Y-273476D01*
X288851Y-273491D01*
X288836Y-273498D01*
X288829Y-273502D01*
X288895Y-273513D01*
X288958Y-273524D01*
X289014Y-273542D01*
X289069Y-273557D01*
X289117Y-273576D01*
X289162Y-273598D01*
X289202Y-273617D01*
X289240Y-273635D01*
X289269Y-273657D01*
X289299Y-273676D01*
X289321Y-273691D01*
X289339Y-273705D01*
X289354Y-273716D01*
X289365Y-273727D01*
X289369Y-273731D01*
X289373Y-273735D01*
X289402Y-273772D01*
X289432Y-273809D01*
X289476Y-273887D01*
X289506Y-273964D01*
X289528Y-274038D01*
X289543Y-274101D01*
X289547Y-274127D01*
Y-274153D01*
X289550Y-274171D01*
Y-274186D01*
Y-274194D01*
Y-274197D01*
X289547Y-274275D01*
X289535Y-274345D01*
X289517Y-274412D01*
X289498Y-274467D01*
X289476Y-274516D01*
X289461Y-274553D01*
X289447Y-274575D01*
X289443Y-274578D01*
Y-274582D01*
X289399Y-274641D01*
X289354Y-274693D01*
X289306Y-274738D01*
X289262Y-274771D01*
X289221Y-274797D01*
X289188Y-274812D01*
X289165Y-274823D01*
X289162Y-274826D01*
X289158D01*
X289125Y-274837D01*
X289084Y-274849D01*
X289003Y-274867D01*
X288914Y-274878D01*
X288832Y-274889D01*
X288755Y-274893D01*
X288721D01*
X288692Y-274897D01*
X287504D01*
Y-272336D01*
X287845D01*
Y-273472D01*
X288281D01*
X288322Y-273468D01*
X288351D01*
X288377Y-273465D01*
X288396Y-273461D01*
X288411D01*
X288418Y-273457D01*
X288422D01*
X288481Y-273439D01*
X288507Y-273428D01*
X288529Y-273417D01*
X288551Y-273406D01*
X288566Y-273398D01*
X288574Y-273394D01*
X288577Y-273391D01*
X288607Y-273369D01*
X288636Y-273343D01*
X288692Y-273287D01*
X288718Y-273261D01*
X288736Y-273239D01*
X288747Y-273224D01*
X288751Y-273221D01*
X288788Y-273169D01*
X288829Y-273113D01*
X288870Y-273054D01*
X288910Y-272999D01*
X288944Y-272947D01*
X288969Y-272906D01*
X288981Y-272891D01*
X288988Y-272880D01*
X288995Y-272873D01*
Y-272869D01*
X289332Y-272336D01*
X289754D01*
X289314Y-273032D01*
D02*
G37*
G36*
X293598Y-272640D02*
X292336D01*
X292381Y-272703D01*
X292403Y-272728D01*
X292422Y-272754D01*
X292440Y-272777D01*
X292455Y-272791D01*
X292466Y-272802D01*
X292470Y-272806D01*
X292488Y-272825D01*
X292510Y-272843D01*
X292562Y-272891D01*
X292621Y-272947D01*
X292684Y-273002D01*
X292743Y-273050D01*
X292769Y-273073D01*
X292792Y-273095D01*
X292810Y-273110D01*
X292825Y-273121D01*
X292832Y-273128D01*
X292836Y-273132D01*
X292895Y-273184D01*
X292954Y-273232D01*
X293006Y-273280D01*
X293054Y-273321D01*
X293099Y-273361D01*
X293136Y-273398D01*
X293173Y-273431D01*
X293202Y-273461D01*
X293232Y-273491D01*
X293254Y-273513D01*
X293272Y-273531D01*
X293291Y-273550D01*
X293309Y-273572D01*
X293317Y-273580D01*
X293369Y-273642D01*
X293413Y-273698D01*
X293450Y-273753D01*
X293480Y-273798D01*
X293502Y-273838D01*
X293517Y-273868D01*
X293524Y-273887D01*
X293528Y-273894D01*
X293550Y-273950D01*
X293565Y-274005D01*
X293580Y-274057D01*
X293587Y-274101D01*
X293591Y-274142D01*
X293594Y-274171D01*
Y-274190D01*
Y-274197D01*
X293591Y-274253D01*
X293583Y-274305D01*
X293576Y-274357D01*
X293561Y-274401D01*
X293524Y-274490D01*
X293487Y-274560D01*
X293465Y-274593D01*
X293446Y-274619D01*
X293428Y-274645D01*
X293409Y-274664D01*
X293395Y-274678D01*
X293387Y-274693D01*
X293380Y-274697D01*
X293376Y-274701D01*
X293335Y-274738D01*
X293291Y-274771D01*
X293243Y-274797D01*
X293195Y-274819D01*
X293099Y-274856D01*
X293002Y-274882D01*
X292962Y-274889D01*
X292921Y-274897D01*
X292884Y-274900D01*
X292854Y-274904D01*
X292828Y-274908D01*
X292792D01*
X292725Y-274904D01*
X292662Y-274900D01*
X292603Y-274889D01*
X292547Y-274878D01*
X292495Y-274863D01*
X292447Y-274849D01*
X292403Y-274830D01*
X292362Y-274812D01*
X292325Y-274793D01*
X292296Y-274775D01*
X292270Y-274760D01*
X292248Y-274745D01*
X292229Y-274734D01*
X292218Y-274723D01*
X292211Y-274719D01*
X292207Y-274715D01*
X292170Y-274678D01*
X292137Y-274638D01*
X292103Y-274593D01*
X292077Y-274549D01*
X292033Y-274460D01*
X292003Y-274371D01*
X291992Y-274331D01*
X291981Y-274290D01*
X291974Y-274257D01*
X291966Y-274227D01*
X291963Y-274201D01*
Y-274183D01*
X291959Y-274171D01*
Y-274168D01*
X292281Y-274134D01*
X292288Y-274220D01*
X292303Y-274294D01*
X292325Y-274360D01*
X292351Y-274412D01*
X292373Y-274456D01*
X292396Y-274486D01*
X292410Y-274504D01*
X292418Y-274512D01*
X292473Y-274556D01*
X292532Y-274590D01*
X292595Y-274616D01*
X292651Y-274630D01*
X292703Y-274641D01*
X292747Y-274645D01*
X292762Y-274649D01*
X292784D01*
X292862Y-274645D01*
X292932Y-274630D01*
X292991Y-274608D01*
X293043Y-274586D01*
X293084Y-274560D01*
X293110Y-274541D01*
X293128Y-274527D01*
X293136Y-274519D01*
X293180Y-274467D01*
X293213Y-274416D01*
X293239Y-274364D01*
X293254Y-274312D01*
X293265Y-274271D01*
X293269Y-274234D01*
X293272Y-274212D01*
Y-274208D01*
Y-274205D01*
X293265Y-274138D01*
X293250Y-274068D01*
X293224Y-274005D01*
X293198Y-273946D01*
X293169Y-273898D01*
X293143Y-273857D01*
X293136Y-273842D01*
X293128Y-273831D01*
X293121Y-273827D01*
Y-273824D01*
X293091Y-273783D01*
X293054Y-273742D01*
X293014Y-273698D01*
X292969Y-273654D01*
X292877Y-273565D01*
X292784Y-273476D01*
X292736Y-273435D01*
X292695Y-273398D01*
X292655Y-273365D01*
X292621Y-273335D01*
X292595Y-273313D01*
X292573Y-273295D01*
X292558Y-273284D01*
X292555Y-273280D01*
X292462Y-273202D01*
X292377Y-273128D01*
X292307Y-273061D01*
X292251Y-273006D01*
X292203Y-272958D01*
X292170Y-272925D01*
X292151Y-272902D01*
X292144Y-272899D01*
Y-272895D01*
X292092Y-272832D01*
X292052Y-272773D01*
X292015Y-272714D01*
X291985Y-272662D01*
X291963Y-272618D01*
X291948Y-272584D01*
X291940Y-272562D01*
X291937Y-272558D01*
Y-272555D01*
X291922Y-272514D01*
X291915Y-272477D01*
X291907Y-272440D01*
X291903Y-272407D01*
X291900Y-272377D01*
Y-272355D01*
Y-272340D01*
Y-272336D01*
X293598D01*
Y-272640D01*
D02*
G37*
G36*
X291607D02*
X290346D01*
X290390Y-272703D01*
X290412Y-272728D01*
X290431Y-272754D01*
X290449Y-272777D01*
X290464Y-272791D01*
X290475Y-272802D01*
X290479Y-272806D01*
X290497Y-272825D01*
X290520Y-272843D01*
X290571Y-272891D01*
X290631Y-272947D01*
X290694Y-273002D01*
X290753Y-273050D01*
X290779Y-273073D01*
X290801Y-273095D01*
X290819Y-273110D01*
X290834Y-273121D01*
X290842Y-273128D01*
X290845Y-273132D01*
X290904Y-273184D01*
X290964Y-273232D01*
X291016Y-273280D01*
X291064Y-273321D01*
X291108Y-273361D01*
X291145Y-273398D01*
X291182Y-273431D01*
X291212Y-273461D01*
X291241Y-273491D01*
X291263Y-273513D01*
X291282Y-273531D01*
X291300Y-273550D01*
X291319Y-273572D01*
X291326Y-273580D01*
X291378Y-273642D01*
X291423Y-273698D01*
X291459Y-273753D01*
X291489Y-273798D01*
X291511Y-273838D01*
X291526Y-273868D01*
X291533Y-273887D01*
X291537Y-273894D01*
X291559Y-273950D01*
X291574Y-274005D01*
X291589Y-274057D01*
X291596Y-274101D01*
X291600Y-274142D01*
X291604Y-274171D01*
Y-274190D01*
Y-274197D01*
X291600Y-274253D01*
X291593Y-274305D01*
X291585Y-274357D01*
X291570Y-274401D01*
X291533Y-274490D01*
X291496Y-274560D01*
X291474Y-274593D01*
X291456Y-274619D01*
X291437Y-274645D01*
X291419Y-274664D01*
X291404Y-274678D01*
X291397Y-274693D01*
X291389Y-274697D01*
X291386Y-274701D01*
X291345Y-274738D01*
X291300Y-274771D01*
X291252Y-274797D01*
X291204Y-274819D01*
X291108Y-274856D01*
X291012Y-274882D01*
X290971Y-274889D01*
X290930Y-274897D01*
X290893Y-274900D01*
X290864Y-274904D01*
X290838Y-274908D01*
X290801D01*
X290734Y-274904D01*
X290671Y-274900D01*
X290612Y-274889D01*
X290557Y-274878D01*
X290505Y-274863D01*
X290457Y-274849D01*
X290412Y-274830D01*
X290372Y-274812D01*
X290335Y-274793D01*
X290305Y-274775D01*
X290279Y-274760D01*
X290257Y-274745D01*
X290238Y-274734D01*
X290227Y-274723D01*
X290220Y-274719D01*
X290216Y-274715D01*
X290179Y-274678D01*
X290146Y-274638D01*
X290113Y-274593D01*
X290087Y-274549D01*
X290042Y-274460D01*
X290013Y-274371D01*
X290002Y-274331D01*
X289991Y-274290D01*
X289983Y-274257D01*
X289976Y-274227D01*
X289972Y-274201D01*
Y-274183D01*
X289968Y-274171D01*
Y-274168D01*
X290290Y-274134D01*
X290298Y-274220D01*
X290313Y-274294D01*
X290335Y-274360D01*
X290361Y-274412D01*
X290383Y-274456D01*
X290405Y-274486D01*
X290420Y-274504D01*
X290427Y-274512D01*
X290483Y-274556D01*
X290542Y-274590D01*
X290605Y-274616D01*
X290660Y-274630D01*
X290712Y-274641D01*
X290757Y-274645D01*
X290771Y-274649D01*
X290793D01*
X290871Y-274645D01*
X290942Y-274630D01*
X291001Y-274608D01*
X291053Y-274586D01*
X291093Y-274560D01*
X291119Y-274541D01*
X291138Y-274527D01*
X291145Y-274519D01*
X291189Y-274467D01*
X291223Y-274416D01*
X291249Y-274364D01*
X291263Y-274312D01*
X291274Y-274271D01*
X291278Y-274234D01*
X291282Y-274212D01*
Y-274208D01*
Y-274205D01*
X291274Y-274138D01*
X291260Y-274068D01*
X291234Y-274005D01*
X291208Y-273946D01*
X291178Y-273898D01*
X291152Y-273857D01*
X291145Y-273842D01*
X291138Y-273831D01*
X291130Y-273827D01*
Y-273824D01*
X291101Y-273783D01*
X291064Y-273742D01*
X291023Y-273698D01*
X290979Y-273654D01*
X290886Y-273565D01*
X290793Y-273476D01*
X290745Y-273435D01*
X290705Y-273398D01*
X290664Y-273365D01*
X290631Y-273335D01*
X290605Y-273313D01*
X290583Y-273295D01*
X290568Y-273284D01*
X290564Y-273280D01*
X290472Y-273202D01*
X290387Y-273128D01*
X290316Y-273061D01*
X290261Y-273006D01*
X290213Y-272958D01*
X290179Y-272925D01*
X290161Y-272902D01*
X290153Y-272899D01*
Y-272895D01*
X290102Y-272832D01*
X290061Y-272773D01*
X290024Y-272714D01*
X289994Y-272662D01*
X289972Y-272618D01*
X289957Y-272584D01*
X289950Y-272562D01*
X289946Y-272558D01*
Y-272555D01*
X289931Y-272514D01*
X289924Y-272477D01*
X289917Y-272440D01*
X289913Y-272407D01*
X289909Y-272377D01*
Y-272355D01*
Y-272340D01*
Y-272336D01*
X291607D01*
Y-272640D01*
D02*
G37*
G36*
X146844Y-347445D02*
X146893Y-347452D01*
X146952Y-347463D01*
X147018Y-347482D01*
X147085Y-347504D01*
X147152Y-347534D01*
X147155D01*
X147159Y-347537D01*
X147181Y-347549D01*
X147214Y-347571D01*
X147251Y-347597D01*
X147296Y-347634D01*
X147340Y-347674D01*
X147385Y-347723D01*
X147422Y-347778D01*
X147425Y-347785D01*
X147436Y-347804D01*
X147451Y-347837D01*
X147470Y-347878D01*
X147488Y-347926D01*
X147503Y-347982D01*
X147514Y-348044D01*
X147518Y-348107D01*
Y-348115D01*
Y-348137D01*
X147514Y-348166D01*
X147507Y-348207D01*
X147496Y-348255D01*
X147477Y-348307D01*
X147455Y-348359D01*
X147425Y-348411D01*
X147422Y-348418D01*
X147411Y-348433D01*
X147388Y-348459D01*
X147359Y-348488D01*
X147322Y-348522D01*
X147277Y-348559D01*
X147226Y-348592D01*
X147163Y-348625D01*
X147166D01*
X147174Y-348629D01*
X147185Y-348633D01*
X147200Y-348636D01*
X147240Y-348651D01*
X147292Y-348673D01*
X147351Y-348703D01*
X147411Y-348740D01*
X147466Y-348788D01*
X147518Y-348844D01*
X147522Y-348851D01*
X147536Y-348873D01*
X147559Y-348910D01*
X147581Y-348958D01*
X147603Y-349018D01*
X147625Y-349088D01*
X147640Y-349169D01*
X147644Y-349258D01*
Y-349262D01*
Y-349273D01*
Y-349291D01*
X147640Y-349313D01*
X147636Y-349343D01*
X147629Y-349376D01*
X147622Y-349413D01*
X147614Y-349454D01*
X147584Y-349543D01*
X147562Y-349591D01*
X147540Y-349635D01*
X147511Y-349683D01*
X147477Y-349732D01*
X147440Y-349780D01*
X147396Y-349824D01*
X147392Y-349828D01*
X147385Y-349835D01*
X147370Y-349846D01*
X147351Y-349861D01*
X147329Y-349880D01*
X147300Y-349898D01*
X147266Y-349920D01*
X147226Y-349939D01*
X147185Y-349961D01*
X147137Y-349983D01*
X147089Y-350002D01*
X147033Y-350020D01*
X146974Y-350035D01*
X146911Y-350046D01*
X146848Y-350054D01*
X146778Y-350057D01*
X146745D01*
X146722Y-350054D01*
X146693Y-350050D01*
X146660Y-350046D01*
X146623Y-350039D01*
X146582Y-350031D01*
X146493Y-350009D01*
X146400Y-349972D01*
X146352Y-349950D01*
X146308Y-349924D01*
X146264Y-349891D01*
X146219Y-349857D01*
X146215Y-349854D01*
X146208Y-349846D01*
X146197Y-349835D01*
X146186Y-349820D01*
X146167Y-349802D01*
X146149Y-349776D01*
X146127Y-349750D01*
X146105Y-349717D01*
X146082Y-349680D01*
X146060Y-349643D01*
X146019Y-349554D01*
X145986Y-349450D01*
X145975Y-349395D01*
X145968Y-349336D01*
X146282Y-349295D01*
Y-349299D01*
X146286Y-349306D01*
X146290Y-349321D01*
X146293Y-349339D01*
X146297Y-349362D01*
X146304Y-349388D01*
X146323Y-349443D01*
X146349Y-349510D01*
X146382Y-349572D01*
X146419Y-349632D01*
X146463Y-349683D01*
X146471Y-349687D01*
X146486Y-349702D01*
X146515Y-349721D01*
X146552Y-349739D01*
X146597Y-349761D01*
X146652Y-349780D01*
X146715Y-349795D01*
X146782Y-349798D01*
X146804D01*
X146819Y-349795D01*
X146859Y-349791D01*
X146911Y-349780D01*
X146970Y-349761D01*
X147033Y-349735D01*
X147096Y-349698D01*
X147155Y-349646D01*
X147163Y-349639D01*
X147181Y-349617D01*
X147203Y-349584D01*
X147233Y-349539D01*
X147263Y-349484D01*
X147285Y-349421D01*
X147303Y-349347D01*
X147311Y-349265D01*
Y-349262D01*
Y-349254D01*
Y-349243D01*
X147307Y-349228D01*
X147303Y-349188D01*
X147292Y-349140D01*
X147277Y-349080D01*
X147251Y-349021D01*
X147214Y-348962D01*
X147166Y-348906D01*
X147159Y-348899D01*
X147141Y-348884D01*
X147111Y-348862D01*
X147070Y-348836D01*
X147018Y-348810D01*
X146956Y-348788D01*
X146885Y-348773D01*
X146808Y-348766D01*
X146774D01*
X146748Y-348770D01*
X146715Y-348773D01*
X146678Y-348781D01*
X146634Y-348788D01*
X146586Y-348799D01*
X146623Y-348522D01*
X146641D01*
X146656Y-348525D01*
X146704D01*
X146745Y-348518D01*
X146793Y-348511D01*
X146848Y-348499D01*
X146911Y-348481D01*
X146970Y-348455D01*
X147033Y-348422D01*
X147037D01*
X147041Y-348418D01*
X147059Y-348403D01*
X147085Y-348377D01*
X147115Y-348344D01*
X147144Y-348296D01*
X147170Y-348240D01*
X147189Y-348178D01*
X147196Y-348141D01*
Y-348100D01*
Y-348096D01*
Y-348093D01*
Y-348070D01*
X147189Y-348041D01*
X147181Y-348000D01*
X147166Y-347956D01*
X147148Y-347907D01*
X147118Y-347859D01*
X147078Y-347815D01*
X147074Y-347811D01*
X147055Y-347797D01*
X147029Y-347778D01*
X146996Y-347756D01*
X146952Y-347737D01*
X146900Y-347719D01*
X146841Y-347704D01*
X146774Y-347700D01*
X146745D01*
X146711Y-347708D01*
X146667Y-347715D01*
X146619Y-347730D01*
X146571Y-347748D01*
X146519Y-347778D01*
X146471Y-347815D01*
X146467Y-347819D01*
X146452Y-347837D01*
X146430Y-347863D01*
X146404Y-347900D01*
X146378Y-347948D01*
X146352Y-348007D01*
X146330Y-348078D01*
X146315Y-348159D01*
X146001Y-348104D01*
Y-348100D01*
X146005Y-348089D01*
X146008Y-348074D01*
X146012Y-348052D01*
X146019Y-348026D01*
X146030Y-347996D01*
X146053Y-347926D01*
X146090Y-347845D01*
X146134Y-347763D01*
X146190Y-347686D01*
X146260Y-347615D01*
X146264Y-347611D01*
X146271Y-347608D01*
X146282Y-347600D01*
X146297Y-347589D01*
X146315Y-347574D01*
X146341Y-347560D01*
X146367Y-347545D01*
X146400Y-347526D01*
X146475Y-347497D01*
X146560Y-347467D01*
X146660Y-347449D01*
X146711Y-347441D01*
X146804D01*
X146844Y-347445D01*
D02*
G37*
G36*
X144884D02*
X144913Y-347449D01*
X144950Y-347452D01*
X144991Y-347460D01*
X145031Y-347467D01*
X145128Y-347493D01*
X145224Y-347530D01*
X145272Y-347552D01*
X145320Y-347578D01*
X145364Y-347611D01*
X145405Y-347649D01*
X145409Y-347652D01*
X145416Y-347656D01*
X145424Y-347671D01*
X145439Y-347686D01*
X145457Y-347704D01*
X145475Y-347730D01*
X145494Y-347756D01*
X145516Y-347789D01*
X145553Y-347859D01*
X145590Y-347948D01*
X145605Y-347993D01*
X145612Y-348044D01*
X145620Y-348096D01*
X145624Y-348152D01*
Y-348159D01*
Y-348178D01*
X145620Y-348207D01*
X145616Y-348248D01*
X145609Y-348292D01*
X145594Y-348344D01*
X145579Y-348400D01*
X145557Y-348455D01*
X145553Y-348463D01*
X145546Y-348481D01*
X145531Y-348511D01*
X145509Y-348551D01*
X145479Y-348596D01*
X145442Y-348651D01*
X145398Y-348707D01*
X145346Y-348770D01*
X145339Y-348777D01*
X145320Y-348799D01*
X145302Y-348818D01*
X145283Y-348836D01*
X145261Y-348858D01*
X145231Y-348888D01*
X145202Y-348918D01*
X145165Y-348951D01*
X145128Y-348988D01*
X145083Y-349029D01*
X145035Y-349069D01*
X144983Y-349117D01*
X144924Y-349166D01*
X144865Y-349217D01*
X144861Y-349221D01*
X144854Y-349228D01*
X144839Y-349239D01*
X144821Y-349254D01*
X144798Y-349276D01*
X144773Y-349299D01*
X144713Y-349347D01*
X144650Y-349402D01*
X144591Y-349458D01*
X144539Y-349506D01*
X144517Y-349524D01*
X144499Y-349543D01*
X144495Y-349547D01*
X144484Y-349558D01*
X144469Y-349572D01*
X144451Y-349595D01*
X144432Y-349621D01*
X144410Y-349646D01*
X144366Y-349709D01*
X145627D01*
Y-350013D01*
X143929D01*
Y-350009D01*
Y-349994D01*
Y-349972D01*
X143933Y-349942D01*
X143936Y-349909D01*
X143944Y-349872D01*
X143951Y-349835D01*
X143966Y-349795D01*
Y-349791D01*
X143970Y-349787D01*
X143977Y-349765D01*
X143992Y-349732D01*
X144014Y-349687D01*
X144044Y-349635D01*
X144081Y-349576D01*
X144121Y-349517D01*
X144173Y-349454D01*
Y-349450D01*
X144181Y-349447D01*
X144199Y-349425D01*
X144232Y-349391D01*
X144280Y-349343D01*
X144336Y-349288D01*
X144406Y-349221D01*
X144491Y-349147D01*
X144584Y-349069D01*
X144588Y-349066D01*
X144602Y-349055D01*
X144624Y-349036D01*
X144650Y-349014D01*
X144684Y-348984D01*
X144724Y-348951D01*
X144765Y-348914D01*
X144813Y-348873D01*
X144906Y-348784D01*
X144998Y-348696D01*
X145043Y-348651D01*
X145083Y-348607D01*
X145120Y-348566D01*
X145150Y-348525D01*
Y-348522D01*
X145157Y-348518D01*
X145165Y-348507D01*
X145172Y-348492D01*
X145198Y-348451D01*
X145228Y-348403D01*
X145254Y-348344D01*
X145279Y-348281D01*
X145294Y-348211D01*
X145302Y-348144D01*
Y-348141D01*
Y-348137D01*
X145298Y-348115D01*
X145294Y-348078D01*
X145283Y-348037D01*
X145268Y-347985D01*
X145242Y-347933D01*
X145209Y-347882D01*
X145165Y-347830D01*
X145157Y-347822D01*
X145139Y-347808D01*
X145113Y-347789D01*
X145072Y-347763D01*
X145020Y-347741D01*
X144961Y-347719D01*
X144891Y-347704D01*
X144813Y-347700D01*
X144791D01*
X144776Y-347704D01*
X144732Y-347708D01*
X144680Y-347719D01*
X144624Y-347734D01*
X144562Y-347760D01*
X144502Y-347793D01*
X144447Y-347837D01*
X144439Y-347845D01*
X144425Y-347863D01*
X144403Y-347893D01*
X144380Y-347937D01*
X144354Y-347989D01*
X144332Y-348056D01*
X144317Y-348130D01*
X144310Y-348215D01*
X143988Y-348181D01*
Y-348178D01*
X143992Y-348166D01*
Y-348148D01*
X143995Y-348122D01*
X144003Y-348093D01*
X144010Y-348059D01*
X144021Y-348019D01*
X144033Y-347978D01*
X144062Y-347889D01*
X144106Y-347800D01*
X144132Y-347756D01*
X144166Y-347711D01*
X144199Y-347671D01*
X144236Y-347634D01*
X144240Y-347630D01*
X144247Y-347626D01*
X144258Y-347615D01*
X144277Y-347604D01*
X144299Y-347589D01*
X144325Y-347574D01*
X144354Y-347556D01*
X144391Y-347537D01*
X144432Y-347519D01*
X144476Y-347500D01*
X144525Y-347486D01*
X144576Y-347471D01*
X144632Y-347460D01*
X144691Y-347449D01*
X144754Y-347445D01*
X144821Y-347441D01*
X144858D01*
X144884Y-347445D01*
D02*
G37*
G36*
X142741Y-347456D02*
X142774D01*
X142852Y-347460D01*
X142934Y-347471D01*
X143022Y-347482D01*
X143104Y-347500D01*
X143145Y-347512D01*
X143178Y-347523D01*
X143182D01*
X143185Y-347526D01*
X143207Y-347537D01*
X143241Y-347552D01*
X143281Y-347578D01*
X143326Y-347611D01*
X143374Y-347656D01*
X143418Y-347708D01*
X143463Y-347767D01*
Y-347771D01*
X143466Y-347774D01*
X143481Y-347797D01*
X143496Y-347833D01*
X143518Y-347882D01*
X143537Y-347937D01*
X143555Y-348004D01*
X143566Y-348074D01*
X143570Y-348152D01*
Y-348155D01*
Y-348163D01*
Y-348178D01*
X143566Y-348196D01*
Y-348222D01*
X143563Y-348248D01*
X143548Y-348311D01*
X143526Y-348385D01*
X143496Y-348463D01*
X143452Y-348540D01*
X143422Y-348577D01*
X143392Y-348614D01*
X143389Y-348618D01*
X143385Y-348622D01*
X143374Y-348633D01*
X143359Y-348644D01*
X143341Y-348659D01*
X143318Y-348673D01*
X143289Y-348692D01*
X143259Y-348714D01*
X143222Y-348733D01*
X143182Y-348751D01*
X143137Y-348773D01*
X143089Y-348792D01*
X143034Y-348807D01*
X142978Y-348825D01*
X142915Y-348836D01*
X142849Y-348847D01*
X142856Y-348851D01*
X142871Y-348858D01*
X142893Y-348873D01*
X142922Y-348888D01*
X142989Y-348929D01*
X143022Y-348955D01*
X143052Y-348977D01*
X143059Y-348984D01*
X143078Y-349003D01*
X143107Y-349032D01*
X143145Y-349069D01*
X143185Y-349121D01*
X143233Y-349177D01*
X143281Y-349243D01*
X143333Y-349317D01*
X143773Y-350013D01*
X143352D01*
X143015Y-349480D01*
Y-349476D01*
X143008Y-349469D01*
X143000Y-349458D01*
X142989Y-349443D01*
X142963Y-349402D01*
X142930Y-349351D01*
X142889Y-349295D01*
X142849Y-349236D01*
X142808Y-349180D01*
X142771Y-349129D01*
X142767Y-349125D01*
X142756Y-349110D01*
X142737Y-349088D01*
X142712Y-349062D01*
X142656Y-349006D01*
X142627Y-348980D01*
X142597Y-348958D01*
X142593Y-348955D01*
X142586Y-348951D01*
X142571Y-348943D01*
X142549Y-348932D01*
X142527Y-348921D01*
X142501Y-348910D01*
X142441Y-348892D01*
X142438D01*
X142430Y-348888D01*
X142416D01*
X142397Y-348884D01*
X142371Y-348881D01*
X142342D01*
X142301Y-348877D01*
X141864D01*
Y-350013D01*
X141524D01*
Y-347452D01*
X142712D01*
X142741Y-347456D01*
D02*
G37*
G36*
X147301Y-353507D02*
X147649D01*
Y-353796D01*
X147301D01*
Y-354410D01*
X146987D01*
Y-353796D01*
X145873D01*
Y-353507D01*
X147046Y-351850D01*
X147301D01*
Y-353507D01*
D02*
G37*
G36*
X144900Y-351842D02*
X144930Y-351846D01*
X144967Y-351850D01*
X145007Y-351857D01*
X145048Y-351865D01*
X145144Y-351890D01*
X145240Y-351927D01*
X145289Y-351950D01*
X145337Y-351975D01*
X145381Y-352009D01*
X145422Y-352046D01*
X145425Y-352049D01*
X145433Y-352053D01*
X145440Y-352068D01*
X145455Y-352083D01*
X145474Y-352101D01*
X145492Y-352127D01*
X145511Y-352153D01*
X145533Y-352186D01*
X145570Y-352257D01*
X145607Y-352345D01*
X145622Y-352390D01*
X145629Y-352442D01*
X145636Y-352494D01*
X145640Y-352549D01*
Y-352556D01*
Y-352575D01*
X145636Y-352605D01*
X145633Y-352645D01*
X145625Y-352690D01*
X145610Y-352741D01*
X145596Y-352797D01*
X145573Y-352852D01*
X145570Y-352860D01*
X145562Y-352878D01*
X145548Y-352908D01*
X145525Y-352949D01*
X145496Y-352993D01*
X145459Y-353048D01*
X145414Y-353104D01*
X145363Y-353167D01*
X145355Y-353174D01*
X145337Y-353197D01*
X145318Y-353215D01*
X145300Y-353234D01*
X145278Y-353256D01*
X145248Y-353285D01*
X145218Y-353315D01*
X145181Y-353348D01*
X145144Y-353385D01*
X145100Y-353426D01*
X145052Y-353467D01*
X145000Y-353515D01*
X144941Y-353563D01*
X144882Y-353615D01*
X144878Y-353618D01*
X144870Y-353626D01*
X144856Y-353637D01*
X144837Y-353652D01*
X144815Y-353674D01*
X144789Y-353696D01*
X144730Y-353744D01*
X144667Y-353800D01*
X144608Y-353855D01*
X144556Y-353903D01*
X144534Y-353922D01*
X144515Y-353940D01*
X144512Y-353944D01*
X144501Y-353955D01*
X144486Y-353970D01*
X144467Y-353992D01*
X144449Y-354018D01*
X144427Y-354044D01*
X144382Y-354107D01*
X145644D01*
Y-354410D01*
X143946D01*
Y-354406D01*
Y-354392D01*
Y-354369D01*
X143949Y-354340D01*
X143953Y-354307D01*
X143960Y-354270D01*
X143968Y-354233D01*
X143983Y-354192D01*
Y-354188D01*
X143986Y-354184D01*
X143994Y-354162D01*
X144008Y-354129D01*
X144031Y-354084D01*
X144060Y-354033D01*
X144097Y-353974D01*
X144138Y-353914D01*
X144190Y-353851D01*
Y-353848D01*
X144197Y-353844D01*
X144216Y-353822D01*
X144249Y-353788D01*
X144297Y-353740D01*
X144352Y-353685D01*
X144423Y-353618D01*
X144508Y-353544D01*
X144600Y-353467D01*
X144604Y-353463D01*
X144619Y-353452D01*
X144641Y-353433D01*
X144667Y-353411D01*
X144700Y-353381D01*
X144741Y-353348D01*
X144782Y-353311D01*
X144830Y-353271D01*
X144922Y-353182D01*
X145015Y-353093D01*
X145059Y-353048D01*
X145100Y-353004D01*
X145137Y-352963D01*
X145167Y-352923D01*
Y-352919D01*
X145174Y-352915D01*
X145181Y-352904D01*
X145189Y-352889D01*
X145215Y-352849D01*
X145244Y-352801D01*
X145270Y-352741D01*
X145296Y-352678D01*
X145311Y-352608D01*
X145318Y-352542D01*
Y-352538D01*
Y-352534D01*
X145315Y-352512D01*
X145311Y-352475D01*
X145300Y-352434D01*
X145285Y-352382D01*
X145259Y-352331D01*
X145226Y-352279D01*
X145181Y-352227D01*
X145174Y-352220D01*
X145155Y-352205D01*
X145130Y-352186D01*
X145089Y-352161D01*
X145037Y-352138D01*
X144978Y-352116D01*
X144907Y-352101D01*
X144830Y-352098D01*
X144808D01*
X144793Y-352101D01*
X144748Y-352105D01*
X144697Y-352116D01*
X144641Y-352131D01*
X144578Y-352157D01*
X144519Y-352190D01*
X144464Y-352235D01*
X144456Y-352242D01*
X144441Y-352260D01*
X144419Y-352290D01*
X144397Y-352334D01*
X144371Y-352386D01*
X144349Y-352453D01*
X144334Y-352527D01*
X144327Y-352612D01*
X144005Y-352579D01*
Y-352575D01*
X144008Y-352564D01*
Y-352545D01*
X144012Y-352519D01*
X144019Y-352490D01*
X144027Y-352456D01*
X144038Y-352416D01*
X144049Y-352375D01*
X144079Y-352286D01*
X144123Y-352198D01*
X144149Y-352153D01*
X144182Y-352109D01*
X144216Y-352068D01*
X144253Y-352031D01*
X144256Y-352027D01*
X144264Y-352024D01*
X144275Y-352012D01*
X144293Y-352001D01*
X144316Y-351987D01*
X144341Y-351972D01*
X144371Y-351953D01*
X144408Y-351935D01*
X144449Y-351916D01*
X144493Y-351898D01*
X144541Y-351883D01*
X144593Y-351868D01*
X144649Y-351857D01*
X144708Y-351846D01*
X144771Y-351842D01*
X144837Y-351839D01*
X144874D01*
X144900Y-351842D01*
D02*
G37*
G36*
X142758Y-351853D02*
X142791D01*
X142869Y-351857D01*
X142950Y-351868D01*
X143039Y-351879D01*
X143120Y-351898D01*
X143161Y-351909D01*
X143194Y-351920D01*
X143198D01*
X143202Y-351924D01*
X143224Y-351935D01*
X143257Y-351950D01*
X143298Y-351975D01*
X143342Y-352009D01*
X143391Y-352053D01*
X143435Y-352105D01*
X143479Y-352164D01*
Y-352168D01*
X143483Y-352172D01*
X143498Y-352194D01*
X143513Y-352231D01*
X143535Y-352279D01*
X143553Y-352334D01*
X143572Y-352401D01*
X143583Y-352471D01*
X143587Y-352549D01*
Y-352553D01*
Y-352560D01*
Y-352575D01*
X143583Y-352593D01*
Y-352619D01*
X143579Y-352645D01*
X143564Y-352708D01*
X143542Y-352782D01*
X143513Y-352860D01*
X143468Y-352938D01*
X143439Y-352975D01*
X143409Y-353011D01*
X143405Y-353015D01*
X143402Y-353019D01*
X143391Y-353030D01*
X143376Y-353041D01*
X143357Y-353056D01*
X143335Y-353071D01*
X143305Y-353089D01*
X143276Y-353111D01*
X143239Y-353130D01*
X143198Y-353148D01*
X143154Y-353171D01*
X143106Y-353189D01*
X143050Y-353204D01*
X142995Y-353222D01*
X142932Y-353234D01*
X142865Y-353245D01*
X142873Y-353248D01*
X142887Y-353256D01*
X142910Y-353271D01*
X142939Y-353285D01*
X143006Y-353326D01*
X143039Y-353352D01*
X143069Y-353374D01*
X143076Y-353381D01*
X143095Y-353400D01*
X143124Y-353430D01*
X143161Y-353467D01*
X143202Y-353518D01*
X143250Y-353574D01*
X143298Y-353641D01*
X143350Y-353714D01*
X143790Y-354410D01*
X143368D01*
X143032Y-353877D01*
Y-353874D01*
X143024Y-353866D01*
X143017Y-353855D01*
X143006Y-353840D01*
X142980Y-353800D01*
X142947Y-353748D01*
X142906Y-353692D01*
X142865Y-353633D01*
X142824Y-353578D01*
X142787Y-353526D01*
X142784Y-353522D01*
X142773Y-353507D01*
X142754Y-353485D01*
X142728Y-353459D01*
X142673Y-353404D01*
X142643Y-353378D01*
X142613Y-353356D01*
X142610Y-353352D01*
X142602Y-353348D01*
X142588Y-353341D01*
X142565Y-353330D01*
X142543Y-353319D01*
X142517Y-353308D01*
X142458Y-353289D01*
X142454D01*
X142447Y-353285D01*
X142432D01*
X142414Y-353282D01*
X142388Y-353278D01*
X142358D01*
X142317Y-353274D01*
X141881D01*
Y-354410D01*
X141541D01*
Y-351850D01*
X142728D01*
X142758Y-351853D01*
D02*
G37*
G36*
X425914Y-354863D02*
X424889D01*
X424753Y-355555D01*
X424756Y-355551D01*
X424764Y-355547D01*
X424775Y-355540D01*
X424793Y-355529D01*
X424815Y-355518D01*
X424841Y-355503D01*
X424900Y-355473D01*
X424974Y-355444D01*
X425056Y-355418D01*
X425145Y-355399D01*
X425189Y-355392D01*
X425271D01*
X425293Y-355396D01*
X425322Y-355399D01*
X425356Y-355403D01*
X425393Y-355411D01*
X425433Y-355422D01*
X425522Y-355448D01*
X425570Y-355466D01*
X425618Y-355492D01*
X425666Y-355518D01*
X425714Y-355547D01*
X425759Y-355585D01*
X425803Y-355625D01*
X425807Y-355629D01*
X425814Y-355636D01*
X425826Y-355647D01*
X425840Y-355666D01*
X425859Y-355692D01*
X425877Y-355718D01*
X425900Y-355751D01*
X425922Y-355788D01*
X425940Y-355829D01*
X425962Y-355873D01*
X425981Y-355925D01*
X425999Y-355977D01*
X426014Y-356032D01*
X426025Y-356095D01*
X426033Y-356158D01*
X426036Y-356225D01*
Y-356228D01*
Y-356239D01*
Y-356258D01*
X426033Y-356284D01*
X426029Y-356313D01*
X426025Y-356347D01*
X426018Y-356387D01*
X426011Y-356428D01*
X425988Y-356524D01*
X425951Y-356624D01*
X425929Y-356676D01*
X425900Y-356724D01*
X425870Y-356776D01*
X425833Y-356824D01*
X425829Y-356828D01*
X425822Y-356839D01*
X425807Y-356854D01*
X425788Y-356872D01*
X425763Y-356894D01*
X425733Y-356924D01*
X425696Y-356950D01*
X425655Y-356979D01*
X425611Y-357009D01*
X425559Y-357035D01*
X425504Y-357061D01*
X425444Y-357087D01*
X425382Y-357105D01*
X425311Y-357120D01*
X425237Y-357131D01*
X425160Y-357135D01*
X425126D01*
X425100Y-357131D01*
X425071Y-357127D01*
X425037Y-357124D01*
X424997Y-357120D01*
X424956Y-357109D01*
X424863Y-357087D01*
X424771Y-357053D01*
X424723Y-357031D01*
X424675Y-357005D01*
X424630Y-356976D01*
X424586Y-356942D01*
X424582Y-356939D01*
X424575Y-356935D01*
X424568Y-356920D01*
X424553Y-356905D01*
X424534Y-356887D01*
X424516Y-356865D01*
X424494Y-356835D01*
X424475Y-356802D01*
X424453Y-356768D01*
X424431Y-356728D01*
X424390Y-356639D01*
X424357Y-356535D01*
X424345Y-356480D01*
X424338Y-356421D01*
X424667Y-356395D01*
Y-356399D01*
Y-356406D01*
X424671Y-356417D01*
X424675Y-356435D01*
X424686Y-356476D01*
X424701Y-356532D01*
X424723Y-356587D01*
X424753Y-356650D01*
X424789Y-356706D01*
X424834Y-356757D01*
X424841Y-356761D01*
X424856Y-356776D01*
X424886Y-356794D01*
X424926Y-356817D01*
X424971Y-356839D01*
X425026Y-356857D01*
X425089Y-356872D01*
X425160Y-356876D01*
X425182D01*
X425197Y-356872D01*
X425241Y-356868D01*
X425293Y-356854D01*
X425356Y-356835D01*
X425419Y-356805D01*
X425485Y-356761D01*
X425515Y-356735D01*
X425544Y-356706D01*
X425548Y-356702D01*
X425552Y-356698D01*
X425559Y-356687D01*
X425570Y-356676D01*
X425596Y-356635D01*
X425626Y-356583D01*
X425652Y-356521D01*
X425677Y-356443D01*
X425696Y-356350D01*
X425703Y-356302D01*
Y-356251D01*
Y-356247D01*
Y-356239D01*
Y-356225D01*
X425700Y-356206D01*
Y-356184D01*
X425696Y-356158D01*
X425685Y-356099D01*
X425666Y-356029D01*
X425640Y-355958D01*
X425603Y-355892D01*
X425552Y-355829D01*
Y-355825D01*
X425544Y-355821D01*
X425526Y-355803D01*
X425492Y-355777D01*
X425448Y-355747D01*
X425389Y-355721D01*
X425322Y-355696D01*
X425245Y-355677D01*
X425200Y-355670D01*
X425130D01*
X425100Y-355673D01*
X425063Y-355677D01*
X425019Y-355688D01*
X424974Y-355699D01*
X424926Y-355718D01*
X424878Y-355740D01*
X424875Y-355744D01*
X424860Y-355751D01*
X424838Y-355769D01*
X424808Y-355788D01*
X424778Y-355814D01*
X424749Y-355847D01*
X424716Y-355880D01*
X424690Y-355921D01*
X424394Y-355880D01*
X424642Y-354563D01*
X425914D01*
Y-354863D01*
D02*
G37*
G36*
X422936Y-354534D02*
X423010Y-354537D01*
X423084Y-354545D01*
X423158Y-354556D01*
X423221Y-354567D01*
X423224D01*
X423232Y-354571D01*
X423243D01*
X423258Y-354578D01*
X423298Y-354589D01*
X423350Y-354608D01*
X423409Y-354634D01*
X423472Y-354667D01*
X423535Y-354704D01*
X423594Y-354752D01*
X423598Y-354756D01*
X423602Y-354759D01*
X423613Y-354770D01*
X423628Y-354782D01*
X423665Y-354819D01*
X423709Y-354870D01*
X423757Y-354933D01*
X423809Y-355007D01*
X423857Y-355092D01*
X423898Y-355189D01*
Y-355192D01*
X423902Y-355200D01*
X423909Y-355215D01*
X423913Y-355237D01*
X423924Y-355263D01*
X423931Y-355292D01*
X423939Y-355326D01*
X423950Y-355366D01*
X423961Y-355407D01*
X423968Y-355455D01*
X423987Y-355559D01*
X423998Y-355673D01*
X424001Y-355799D01*
Y-355803D01*
Y-355810D01*
Y-355829D01*
Y-355847D01*
X423998Y-355873D01*
Y-355903D01*
X423994Y-355973D01*
X423983Y-356054D01*
X423972Y-356139D01*
X423953Y-356228D01*
X423931Y-356317D01*
Y-356321D01*
X423927Y-356328D01*
X423924Y-356339D01*
X423920Y-356354D01*
X423905Y-356395D01*
X423883Y-356447D01*
X423861Y-356506D01*
X423831Y-356565D01*
X423794Y-356628D01*
X423757Y-356687D01*
X423753Y-356695D01*
X423739Y-356713D01*
X423716Y-356739D01*
X423687Y-356772D01*
X423654Y-356809D01*
X423613Y-356846D01*
X423572Y-356887D01*
X423524Y-356920D01*
X423517Y-356924D01*
X423502Y-356935D01*
X423476Y-356950D01*
X423439Y-356968D01*
X423395Y-356991D01*
X423343Y-357009D01*
X423284Y-357031D01*
X423217Y-357050D01*
X423210D01*
X423199Y-357053D01*
X423187Y-357057D01*
X423150Y-357061D01*
X423099Y-357068D01*
X423039Y-357076D01*
X422969Y-357083D01*
X422891Y-357087D01*
X422806Y-357090D01*
X421885D01*
Y-354530D01*
X422869D01*
X422936Y-354534D01*
D02*
G37*
G36*
X470089Y-355315D02*
X470115D01*
X470145Y-355319D01*
X470215Y-355334D01*
X470293Y-355353D01*
X470374Y-355382D01*
X470455Y-355427D01*
X470496Y-355452D01*
X470533Y-355482D01*
X470537Y-355486D01*
X470541Y-355489D01*
X470552Y-355501D01*
X470563Y-355512D01*
X470581Y-355530D01*
X470596Y-355552D01*
X470637Y-355604D01*
X470677Y-355671D01*
X470714Y-355752D01*
X470748Y-355845D01*
X470770Y-355948D01*
X470455Y-355974D01*
Y-355970D01*
X470452Y-355967D01*
X470448Y-355944D01*
X470437Y-355911D01*
X470422Y-355871D01*
X470407Y-355826D01*
X470385Y-355782D01*
X470359Y-355741D01*
X470333Y-355708D01*
X470326Y-355700D01*
X470311Y-355686D01*
X470285Y-355663D01*
X470248Y-355637D01*
X470200Y-355615D01*
X470148Y-355593D01*
X470085Y-355578D01*
X470019Y-355571D01*
X469993D01*
X469963Y-355574D01*
X469930Y-355582D01*
X469886Y-355593D01*
X469841Y-355608D01*
X469797Y-355626D01*
X469752Y-355656D01*
X469745Y-355660D01*
X469727Y-355674D01*
X469701Y-355700D01*
X469667Y-355737D01*
X469630Y-355782D01*
X469590Y-355834D01*
X469553Y-355900D01*
X469516Y-355974D01*
Y-355978D01*
X469512Y-355985D01*
X469508Y-355996D01*
X469501Y-356011D01*
X469497Y-356033D01*
X469490Y-356059D01*
X469482Y-356089D01*
X469475Y-356126D01*
X469464Y-356167D01*
X469456Y-356211D01*
X469449Y-356259D01*
X469445Y-356311D01*
X469438Y-356370D01*
X469434Y-356429D01*
X469430Y-356496D01*
Y-356562D01*
X469434Y-356559D01*
X469449Y-356537D01*
X469475Y-356507D01*
X469508Y-356470D01*
X469545Y-356426D01*
X469593Y-356385D01*
X469645Y-356344D01*
X469704Y-356307D01*
X469708D01*
X469712Y-356304D01*
X469734Y-356292D01*
X469767Y-356281D01*
X469812Y-356263D01*
X469863Y-356248D01*
X469923Y-356237D01*
X469985Y-356226D01*
X470052Y-356222D01*
X470082D01*
X470104Y-356226D01*
X470133Y-356229D01*
X470163Y-356233D01*
X470200Y-356241D01*
X470237Y-356252D01*
X470322Y-356278D01*
X470367Y-356296D01*
X470411Y-356322D01*
X470455Y-356348D01*
X470504Y-356377D01*
X470548Y-356414D01*
X470589Y-356455D01*
X470592Y-356459D01*
X470600Y-356466D01*
X470611Y-356477D01*
X470622Y-356496D01*
X470640Y-356522D01*
X470659Y-356548D01*
X470677Y-356581D01*
X470700Y-356618D01*
X470722Y-356659D01*
X470740Y-356703D01*
X470759Y-356755D01*
X470777Y-356807D01*
X470788Y-356862D01*
X470799Y-356925D01*
X470807Y-356988D01*
X470811Y-357055D01*
Y-357058D01*
Y-357066D01*
Y-357077D01*
Y-357095D01*
X470807Y-357118D01*
Y-357140D01*
X470796Y-357199D01*
X470785Y-357269D01*
X470766Y-357343D01*
X470740Y-357424D01*
X470703Y-357502D01*
Y-357506D01*
X470700Y-357510D01*
X470692Y-357521D01*
X470685Y-357536D01*
X470663Y-357573D01*
X470629Y-357621D01*
X470589Y-357672D01*
X470541Y-357724D01*
X470481Y-357776D01*
X470418Y-357820D01*
X470415D01*
X470411Y-357824D01*
X470400Y-357832D01*
X470385Y-357835D01*
X470348Y-357854D01*
X470300Y-357872D01*
X470237Y-357894D01*
X470167Y-357909D01*
X470089Y-357924D01*
X470004Y-357928D01*
X469985D01*
X469967Y-357924D01*
X469937D01*
X469904Y-357920D01*
X469867Y-357913D01*
X469823Y-357902D01*
X469778Y-357891D01*
X469727Y-357876D01*
X469675Y-357857D01*
X469623Y-357835D01*
X469567Y-357806D01*
X469516Y-357772D01*
X469464Y-357735D01*
X469412Y-357691D01*
X469364Y-357639D01*
X469360Y-357635D01*
X469353Y-357624D01*
X469342Y-357610D01*
X469327Y-357584D01*
X469305Y-357550D01*
X469286Y-357513D01*
X469264Y-357465D01*
X469242Y-357414D01*
X469216Y-357351D01*
X469194Y-357280D01*
X469175Y-357203D01*
X469157Y-357118D01*
X469138Y-357021D01*
X469127Y-356918D01*
X469120Y-356807D01*
X469116Y-356688D01*
Y-356684D01*
Y-356681D01*
Y-356670D01*
Y-356655D01*
X469120Y-356618D01*
Y-356566D01*
X469123Y-356507D01*
X469131Y-356437D01*
X469138Y-356359D01*
X469149Y-356274D01*
X469164Y-356189D01*
X469183Y-356096D01*
X469205Y-356008D01*
X469231Y-355919D01*
X469264Y-355834D01*
X469301Y-355752D01*
X469342Y-355674D01*
X469390Y-355608D01*
X469393Y-355604D01*
X469401Y-355597D01*
X469416Y-355582D01*
X469434Y-355560D01*
X469456Y-355538D01*
X469486Y-355515D01*
X469523Y-355486D01*
X469560Y-355460D01*
X469604Y-355434D01*
X469653Y-355404D01*
X469708Y-355382D01*
X469764Y-355356D01*
X469826Y-355338D01*
X469893Y-355323D01*
X469963Y-355315D01*
X470037Y-355312D01*
X470067D01*
X470089Y-355315D01*
D02*
G37*
G36*
X467729Y-355327D02*
X467802Y-355330D01*
X467876Y-355338D01*
X467950Y-355349D01*
X468013Y-355360D01*
X468017D01*
X468024Y-355364D01*
X468036D01*
X468050Y-355371D01*
X468091Y-355382D01*
X468143Y-355401D01*
X468202Y-355427D01*
X468265Y-355460D01*
X468328Y-355497D01*
X468387Y-355545D01*
X468391Y-355549D01*
X468395Y-355552D01*
X468406Y-355563D01*
X468420Y-355574D01*
X468457Y-355611D01*
X468502Y-355663D01*
X468550Y-355726D01*
X468602Y-355800D01*
X468650Y-355885D01*
X468690Y-355982D01*
Y-355985D01*
X468694Y-355993D01*
X468702Y-356008D01*
X468705Y-356030D01*
X468716Y-356055D01*
X468724Y-356085D01*
X468731Y-356118D01*
X468742Y-356159D01*
X468753Y-356200D01*
X468761Y-356248D01*
X468779Y-356351D01*
X468790Y-356466D01*
X468794Y-356592D01*
Y-356596D01*
Y-356603D01*
Y-356622D01*
Y-356640D01*
X468790Y-356666D01*
Y-356696D01*
X468787Y-356766D01*
X468776Y-356847D01*
X468764Y-356932D01*
X468746Y-357021D01*
X468724Y-357110D01*
Y-357114D01*
X468720Y-357121D01*
X468716Y-357132D01*
X468713Y-357147D01*
X468698Y-357188D01*
X468676Y-357240D01*
X468653Y-357299D01*
X468624Y-357358D01*
X468587Y-357421D01*
X468550Y-357480D01*
X468546Y-357487D01*
X468531Y-357506D01*
X468509Y-357532D01*
X468480Y-357565D01*
X468446Y-357602D01*
X468406Y-357639D01*
X468365Y-357680D01*
X468317Y-357713D01*
X468309Y-357717D01*
X468295Y-357728D01*
X468269Y-357743D01*
X468232Y-357761D01*
X468187Y-357783D01*
X468135Y-357802D01*
X468076Y-357824D01*
X468010Y-357843D01*
X468002D01*
X467991Y-357846D01*
X467980Y-357850D01*
X467943Y-357854D01*
X467891Y-357861D01*
X467832Y-357869D01*
X467762Y-357876D01*
X467684Y-357880D01*
X467599Y-357883D01*
X466678D01*
Y-355323D01*
X467662D01*
X467729Y-355327D01*
D02*
G37*
G36*
X506148Y-355003D02*
X506222Y-355007D01*
X506296Y-355014D01*
X506370Y-355025D01*
X506433Y-355036D01*
X506436D01*
X506444Y-355040D01*
X506455D01*
X506470Y-355047D01*
X506510Y-355059D01*
X506562Y-355077D01*
X506622Y-355103D01*
X506684Y-355136D01*
X506747Y-355173D01*
X506807Y-355221D01*
X506810Y-355225D01*
X506814Y-355229D01*
X506825Y-355240D01*
X506840Y-355251D01*
X506877Y-355288D01*
X506921Y-355340D01*
X506969Y-355403D01*
X507021Y-355477D01*
X507069Y-355562D01*
X507110Y-355658D01*
Y-355662D01*
X507114Y-355669D01*
X507121Y-355684D01*
X507125Y-355706D01*
X507136Y-355732D01*
X507143Y-355762D01*
X507151Y-355795D01*
X507162Y-355836D01*
X507173Y-355876D01*
X507180Y-355924D01*
X507199Y-356028D01*
X507210Y-356143D01*
X507213Y-356269D01*
Y-356272D01*
Y-356280D01*
Y-356298D01*
Y-356317D01*
X507210Y-356343D01*
Y-356372D01*
X507206Y-356442D01*
X507195Y-356524D01*
X507184Y-356609D01*
X507165Y-356698D01*
X507143Y-356786D01*
Y-356790D01*
X507139Y-356798D01*
X507136Y-356809D01*
X507132Y-356823D01*
X507117Y-356864D01*
X507095Y-356916D01*
X507073Y-356975D01*
X507043Y-357034D01*
X507006Y-357097D01*
X506969Y-357156D01*
X506966Y-357164D01*
X506951Y-357182D01*
X506929Y-357208D01*
X506899Y-357242D01*
X506866Y-357279D01*
X506825Y-357316D01*
X506784Y-357356D01*
X506736Y-357390D01*
X506729Y-357393D01*
X506714Y-357404D01*
X506688Y-357419D01*
X506651Y-357438D01*
X506607Y-357460D01*
X506555Y-357478D01*
X506496Y-357501D01*
X506429Y-357519D01*
X506422D01*
X506411Y-357523D01*
X506399Y-357526D01*
X506362Y-357530D01*
X506311Y-357538D01*
X506251Y-357545D01*
X506181Y-357552D01*
X506104Y-357556D01*
X506018Y-357560D01*
X505097D01*
Y-354999D01*
X506081D01*
X506148Y-355003D01*
D02*
G37*
G36*
X508438Y-354992D02*
X508468Y-354996D01*
X508501Y-354999D01*
X508538Y-355003D01*
X508575Y-355014D01*
X508664Y-355036D01*
X508753Y-355070D01*
X508797Y-355092D01*
X508842Y-355118D01*
X508882Y-355151D01*
X508923Y-355184D01*
X508927Y-355188D01*
X508930Y-355192D01*
X508941Y-355203D01*
X508956Y-355218D01*
X508971Y-355240D01*
X508989Y-355262D01*
X509026Y-355318D01*
X509063Y-355388D01*
X509097Y-355469D01*
X509123Y-355562D01*
X509126Y-355610D01*
X509130Y-355662D01*
Y-355665D01*
Y-355669D01*
Y-355691D01*
X509126Y-355725D01*
X509119Y-355765D01*
X509108Y-355817D01*
X509089Y-355869D01*
X509067Y-355921D01*
X509034Y-355973D01*
X509030Y-355980D01*
X509015Y-355995D01*
X508993Y-356017D01*
X508964Y-356047D01*
X508923Y-356080D01*
X508875Y-356113D01*
X508819Y-356146D01*
X508753Y-356176D01*
X508756D01*
X508764Y-356180D01*
X508775Y-356183D01*
X508790Y-356191D01*
X508834Y-356209D01*
X508886Y-356235D01*
X508941Y-356272D01*
X509001Y-356313D01*
X509056Y-356365D01*
X509108Y-356424D01*
Y-356428D01*
X509112Y-356431D01*
X509126Y-356453D01*
X509149Y-356490D01*
X509171Y-356539D01*
X509193Y-356598D01*
X509215Y-356668D01*
X509230Y-356746D01*
X509234Y-356831D01*
Y-356835D01*
Y-356846D01*
Y-356864D01*
X509230Y-356886D01*
X509226Y-356912D01*
X509223Y-356946D01*
X509215Y-356983D01*
X509204Y-357023D01*
X509178Y-357108D01*
X509160Y-357156D01*
X509134Y-357201D01*
X509108Y-357249D01*
X509078Y-357293D01*
X509041Y-357338D01*
X509001Y-357382D01*
X508997Y-357386D01*
X508989Y-357393D01*
X508978Y-357404D01*
X508960Y-357416D01*
X508934Y-357434D01*
X508908Y-357453D01*
X508875Y-357471D01*
X508838Y-357493D01*
X508797Y-357515D01*
X508749Y-357534D01*
X508697Y-357552D01*
X508645Y-357571D01*
X508586Y-357582D01*
X508523Y-357593D01*
X508460Y-357600D01*
X508390Y-357604D01*
X508353D01*
X508327Y-357600D01*
X508294Y-357597D01*
X508257Y-357593D01*
X508216Y-357586D01*
X508172Y-357575D01*
X508072Y-357549D01*
X508020Y-357530D01*
X507972Y-357512D01*
X507920Y-357486D01*
X507868Y-357456D01*
X507820Y-357423D01*
X507776Y-357382D01*
X507772Y-357379D01*
X507765Y-357371D01*
X507754Y-357360D01*
X507739Y-357342D01*
X507724Y-357319D01*
X507702Y-357293D01*
X507683Y-357264D01*
X507661Y-357227D01*
X507639Y-357190D01*
X507620Y-357145D01*
X507584Y-357053D01*
X507569Y-356997D01*
X507558Y-356942D01*
X507550Y-356883D01*
X507547Y-356823D01*
Y-356820D01*
Y-356812D01*
Y-356798D01*
X507550Y-356783D01*
Y-356761D01*
X507554Y-356735D01*
X507561Y-356676D01*
X507576Y-356609D01*
X507598Y-356542D01*
X507632Y-356472D01*
X507672Y-356405D01*
Y-356402D01*
X507680Y-356398D01*
X507694Y-356380D01*
X507724Y-356350D01*
X507765Y-356313D01*
X507817Y-356276D01*
X507879Y-356235D01*
X507950Y-356202D01*
X508035Y-356176D01*
X508031D01*
X508028Y-356172D01*
X508016Y-356169D01*
X508002Y-356161D01*
X507968Y-356146D01*
X507924Y-356124D01*
X507876Y-356095D01*
X507828Y-356058D01*
X507783Y-356017D01*
X507743Y-355973D01*
X507739Y-355965D01*
X507728Y-355950D01*
X507713Y-355921D01*
X507698Y-355884D01*
X507680Y-355836D01*
X507665Y-355780D01*
X507654Y-355717D01*
X507650Y-355651D01*
Y-355647D01*
Y-355640D01*
Y-355625D01*
X507654Y-355603D01*
X507657Y-355580D01*
X507661Y-355551D01*
X507676Y-355488D01*
X507698Y-355414D01*
X507735Y-355336D01*
X507757Y-355295D01*
X507783Y-355255D01*
X507817Y-355218D01*
X507850Y-355181D01*
X507854Y-355177D01*
X507861Y-355173D01*
X507872Y-355162D01*
X507887Y-355151D01*
X507905Y-355136D01*
X507931Y-355121D01*
X507961Y-355103D01*
X507991Y-355084D01*
X508028Y-355066D01*
X508068Y-355047D01*
X508113Y-355033D01*
X508161Y-355018D01*
X508264Y-354996D01*
X508323Y-354992D01*
X508383Y-354988D01*
X508416D01*
X508438Y-354992D01*
D02*
G37*
G36*
X554212Y-355100D02*
X554208Y-355104D01*
X554201Y-355112D01*
X554186Y-355126D01*
X554171Y-355149D01*
X554149Y-355174D01*
X554120Y-355204D01*
X554090Y-355241D01*
X554057Y-355285D01*
X554023Y-355330D01*
X553983Y-355382D01*
X553942Y-355441D01*
X553901Y-355500D01*
X553857Y-355567D01*
X553813Y-355637D01*
X553768Y-355715D01*
X553724Y-355792D01*
X553720Y-355796D01*
X553713Y-355811D01*
X553701Y-355833D01*
X553683Y-355866D01*
X553664Y-355907D01*
X553642Y-355951D01*
X553616Y-356003D01*
X553590Y-356062D01*
X553561Y-356129D01*
X553528Y-356196D01*
X553498Y-356270D01*
X553468Y-356347D01*
X553409Y-356506D01*
X553354Y-356677D01*
Y-356680D01*
X553350Y-356691D01*
X553346Y-356710D01*
X553339Y-356732D01*
X553332Y-356762D01*
X553324Y-356799D01*
X553313Y-356839D01*
X553306Y-356884D01*
X553295Y-356936D01*
X553283Y-356991D01*
X553265Y-357109D01*
X553246Y-357239D01*
X553235Y-357380D01*
X552913D01*
Y-357376D01*
Y-357365D01*
Y-357350D01*
X552917Y-357328D01*
Y-357298D01*
X552921Y-357261D01*
X552924Y-357221D01*
X552928Y-357176D01*
X552936Y-357124D01*
X552943Y-357073D01*
X552954Y-357010D01*
X552965Y-356947D01*
X552976Y-356880D01*
X552991Y-356806D01*
X553028Y-356654D01*
Y-356651D01*
X553032Y-356636D01*
X553039Y-356614D01*
X553050Y-356580D01*
X553061Y-356543D01*
X553076Y-356499D01*
X553091Y-356447D01*
X553113Y-356392D01*
X553135Y-356329D01*
X553158Y-356266D01*
X553213Y-356125D01*
X553280Y-355977D01*
X553354Y-355829D01*
X553357Y-355826D01*
X553365Y-355811D01*
X553376Y-355792D01*
X553391Y-355763D01*
X553409Y-355729D01*
X553435Y-355689D01*
X553461Y-355644D01*
X553491Y-355596D01*
X553561Y-355489D01*
X553635Y-355378D01*
X553720Y-355263D01*
X553809Y-355156D01*
X552555D01*
Y-354853D01*
X554212D01*
Y-355100D01*
D02*
G37*
G36*
X551130Y-354823D02*
X551204Y-354827D01*
X551278Y-354834D01*
X551352Y-354845D01*
X551415Y-354856D01*
X551419D01*
X551426Y-354860D01*
X551437D01*
X551452Y-354867D01*
X551493Y-354878D01*
X551544Y-354897D01*
X551604Y-354923D01*
X551666Y-354956D01*
X551729Y-354993D01*
X551789Y-355041D01*
X551792Y-355045D01*
X551796Y-355049D01*
X551807Y-355060D01*
X551822Y-355071D01*
X551859Y-355108D01*
X551903Y-355160D01*
X551951Y-355223D01*
X552003Y-355296D01*
X552051Y-355382D01*
X552092Y-355478D01*
Y-355482D01*
X552096Y-355489D01*
X552103Y-355504D01*
X552107Y-355526D01*
X552118Y-355552D01*
X552125Y-355581D01*
X552133Y-355615D01*
X552144Y-355656D01*
X552155Y-355696D01*
X552162Y-355744D01*
X552181Y-355848D01*
X552192Y-355963D01*
X552196Y-356088D01*
Y-356092D01*
Y-356099D01*
Y-356118D01*
Y-356136D01*
X552192Y-356162D01*
Y-356192D01*
X552188Y-356262D01*
X552177Y-356344D01*
X552166Y-356429D01*
X552147Y-356518D01*
X552125Y-356606D01*
Y-356610D01*
X552122Y-356617D01*
X552118Y-356628D01*
X552114Y-356643D01*
X552099Y-356684D01*
X552077Y-356736D01*
X552055Y-356795D01*
X552025Y-356854D01*
X551988Y-356917D01*
X551951Y-356976D01*
X551948Y-356984D01*
X551933Y-357002D01*
X551911Y-357028D01*
X551881Y-357062D01*
X551848Y-357099D01*
X551807Y-357135D01*
X551766Y-357176D01*
X551718Y-357209D01*
X551711Y-357213D01*
X551696Y-357224D01*
X551670Y-357239D01*
X551633Y-357258D01*
X551589Y-357280D01*
X551537Y-357298D01*
X551478Y-357320D01*
X551411Y-357339D01*
X551404D01*
X551393Y-357343D01*
X551382Y-357346D01*
X551345Y-357350D01*
X551293Y-357358D01*
X551234Y-357365D01*
X551163Y-357372D01*
X551086Y-357376D01*
X551000Y-357380D01*
X550079D01*
Y-354819D01*
X551063D01*
X551130Y-354823D01*
D02*
G37*
G36*
X622146Y-37816D02*
X620145D01*
X620148Y-37820D01*
X620163Y-37838D01*
X620185Y-37861D01*
X620211Y-37898D01*
X620245Y-37938D01*
X620282Y-37990D01*
X620322Y-38049D01*
X620363Y-38116D01*
Y-38120D01*
X620367Y-38123D01*
X620381Y-38145D01*
X620400Y-38182D01*
X620422Y-38227D01*
X620448Y-38279D01*
X620474Y-38334D01*
X620500Y-38390D01*
X620522Y-38445D01*
X620219D01*
Y-38441D01*
X620211Y-38434D01*
X620208Y-38419D01*
X620196Y-38401D01*
X620185Y-38379D01*
X620170Y-38353D01*
X620133Y-38290D01*
X620093Y-38216D01*
X620041Y-38142D01*
X619982Y-38064D01*
X619919Y-37986D01*
X619915Y-37983D01*
X619911Y-37979D01*
X619900Y-37968D01*
X619889Y-37953D01*
X619852Y-37920D01*
X619808Y-37875D01*
X619756Y-37831D01*
X619697Y-37783D01*
X619638Y-37742D01*
X619575Y-37705D01*
Y-37502D01*
X622146D01*
Y-37816D01*
D02*
G37*
G36*
X621354Y-38978D02*
X621377Y-38985D01*
X621406Y-38996D01*
X621440Y-39007D01*
X621480Y-39022D01*
X621525Y-39041D01*
X621573Y-39063D01*
X621676Y-39115D01*
X621780Y-39181D01*
X621832Y-39222D01*
X621884Y-39263D01*
X621928Y-39307D01*
X621972Y-39359D01*
X621976Y-39363D01*
X621983Y-39370D01*
X621991Y-39389D01*
X622006Y-39407D01*
X622024Y-39437D01*
X622043Y-39466D01*
X622061Y-39507D01*
X622080Y-39548D01*
X622102Y-39596D01*
X622120Y-39648D01*
X622139Y-39703D01*
X622157Y-39762D01*
X622172Y-39825D01*
X622180Y-39892D01*
X622187Y-39962D01*
X622191Y-40036D01*
Y-40077D01*
X622187Y-40106D01*
Y-40140D01*
X622183Y-40180D01*
X622176Y-40225D01*
X622168Y-40277D01*
X622150Y-40384D01*
X622120Y-40495D01*
X622080Y-40606D01*
X622054Y-40658D01*
X622024Y-40709D01*
X622020Y-40713D01*
X622017Y-40721D01*
X622006Y-40735D01*
X621991Y-40750D01*
X621976Y-40772D01*
X621954Y-40798D01*
X621928Y-40828D01*
X621898Y-40857D01*
X621865Y-40887D01*
X621832Y-40920D01*
X621747Y-40987D01*
X621647Y-41050D01*
X621536Y-41105D01*
X621532D01*
X621521Y-41113D01*
X621502Y-41116D01*
X621480Y-41128D01*
X621451Y-41135D01*
X621414Y-41146D01*
X621373Y-41161D01*
X621329Y-41172D01*
X621280Y-41183D01*
X621225Y-41198D01*
X621110Y-41216D01*
X620981Y-41231D01*
X620848Y-41239D01*
X620844D01*
X620829D01*
X620807D01*
X620781Y-41235D01*
X620744D01*
X620707Y-41231D01*
X620659Y-41227D01*
X620611Y-41220D01*
X620504Y-41202D01*
X620385Y-41176D01*
X620267Y-41139D01*
X620152Y-41087D01*
X620148Y-41083D01*
X620137Y-41080D01*
X620122Y-41072D01*
X620104Y-41057D01*
X620078Y-41043D01*
X620048Y-41024D01*
X619982Y-40976D01*
X619908Y-40913D01*
X619834Y-40839D01*
X619760Y-40754D01*
X619697Y-40654D01*
X619693Y-40650D01*
X619690Y-40639D01*
X619682Y-40624D01*
X619671Y-40606D01*
X619660Y-40576D01*
X619649Y-40547D01*
X619634Y-40510D01*
X619619Y-40469D01*
X619604Y-40425D01*
X619590Y-40376D01*
X619567Y-40273D01*
X619549Y-40154D01*
X619542Y-40032D01*
Y-39995D01*
X619545Y-39970D01*
X619549Y-39936D01*
X619553Y-39895D01*
X619556Y-39855D01*
X619567Y-39807D01*
X619590Y-39707D01*
X619623Y-39596D01*
X619645Y-39540D01*
X619671Y-39489D01*
X619704Y-39437D01*
X619738Y-39385D01*
X619741Y-39381D01*
X619745Y-39374D01*
X619756Y-39359D01*
X619775Y-39340D01*
X619793Y-39322D01*
X619819Y-39296D01*
X619849Y-39270D01*
X619878Y-39241D01*
X619915Y-39211D01*
X619960Y-39181D01*
X620004Y-39148D01*
X620052Y-39118D01*
X620108Y-39093D01*
X620163Y-39063D01*
X620222Y-39041D01*
X620289Y-39019D01*
X620367Y-39352D01*
X620363D01*
X620356Y-39355D01*
X620341Y-39363D01*
X620322Y-39370D01*
X620300Y-39377D01*
X620270Y-39389D01*
X620211Y-39418D01*
X620145Y-39455D01*
X620078Y-39500D01*
X620015Y-39555D01*
X619960Y-39614D01*
X619952Y-39622D01*
X619937Y-39644D01*
X619919Y-39681D01*
X619893Y-39729D01*
X619871Y-39792D01*
X619849Y-39862D01*
X619834Y-39947D01*
X619830Y-40040D01*
Y-40069D01*
X619834Y-40088D01*
Y-40114D01*
X619838Y-40143D01*
X619849Y-40214D01*
X619863Y-40291D01*
X619889Y-40373D01*
X619926Y-40458D01*
X619974Y-40536D01*
Y-40539D01*
X619982Y-40543D01*
X620000Y-40569D01*
X620030Y-40602D01*
X620074Y-40643D01*
X620130Y-40691D01*
X620193Y-40735D01*
X620270Y-40776D01*
X620356Y-40813D01*
X620359D01*
X620367Y-40817D01*
X620378Y-40821D01*
X620396Y-40824D01*
X620418Y-40832D01*
X620444Y-40839D01*
X620507Y-40850D01*
X620581Y-40865D01*
X620663Y-40880D01*
X620751Y-40887D01*
X620848Y-40891D01*
X620851D01*
X620862D01*
X620881D01*
X620903D01*
X620929Y-40887D01*
X620962D01*
X620999Y-40883D01*
X621040Y-40880D01*
X621129Y-40869D01*
X621225Y-40850D01*
X621321Y-40828D01*
X621417Y-40798D01*
X621421D01*
X621428Y-40795D01*
X621440Y-40787D01*
X621458Y-40780D01*
X621502Y-40758D01*
X621554Y-40724D01*
X621614Y-40684D01*
X621676Y-40632D01*
X621732Y-40573D01*
X621784Y-40502D01*
Y-40499D01*
X621787Y-40491D01*
X621795Y-40480D01*
X621802Y-40465D01*
X621810Y-40447D01*
X621821Y-40425D01*
X621843Y-40373D01*
X621865Y-40306D01*
X621884Y-40232D01*
X621898Y-40151D01*
X621902Y-40066D01*
Y-40040D01*
X621898Y-40018D01*
Y-39992D01*
X621895Y-39966D01*
X621880Y-39899D01*
X621861Y-39821D01*
X621832Y-39744D01*
X621791Y-39662D01*
X621769Y-39622D01*
X621739Y-39585D01*
X621736Y-39581D01*
X621732Y-39577D01*
X621721Y-39566D01*
X621710Y-39551D01*
X621691Y-39537D01*
X621669Y-39518D01*
X621647Y-39496D01*
X621617Y-39477D01*
X621584Y-39455D01*
X621547Y-39429D01*
X621510Y-39407D01*
X621465Y-39385D01*
X621417Y-39366D01*
X621366Y-39348D01*
X621310Y-39329D01*
X621251Y-39315D01*
X621336Y-38974D01*
X621340D01*
X621354Y-38978D01*
D02*
G37*
G36*
X591826Y-38307D02*
X591523D01*
Y-36916D01*
X590731D01*
Y-38119D01*
X590427D01*
Y-36916D01*
X589265D01*
Y-36576D01*
X591826D01*
Y-38307D01*
D02*
G37*
G36*
X591193Y-38862D02*
X591201Y-38870D01*
X591204Y-38885D01*
X591215Y-38903D01*
X591226Y-38925D01*
X591241Y-38951D01*
X591278Y-39014D01*
X591319Y-39088D01*
X591371Y-39162D01*
X591430Y-39240D01*
X591493Y-39318D01*
X591497Y-39321D01*
X591500Y-39325D01*
X591511Y-39336D01*
X591523Y-39351D01*
X591560Y-39384D01*
X591604Y-39428D01*
X591656Y-39473D01*
X591715Y-39521D01*
X591774Y-39562D01*
X591837Y-39599D01*
Y-39802D01*
X589265D01*
Y-39488D01*
X591267D01*
X591263Y-39484D01*
X591249Y-39465D01*
X591226Y-39443D01*
X591201Y-39406D01*
X591167Y-39366D01*
X591130Y-39314D01*
X591089Y-39255D01*
X591049Y-39188D01*
Y-39184D01*
X591045Y-39181D01*
X591030Y-39158D01*
X591012Y-39121D01*
X590990Y-39077D01*
X590964Y-39025D01*
X590938Y-38970D01*
X590912Y-38914D01*
X590890Y-38859D01*
X591193D01*
Y-38862D01*
D02*
G37*
G36*
X272253Y-365689D02*
X272335Y-365704D01*
X272405Y-365726D01*
X272464Y-365748D01*
X272512Y-365770D01*
X272549Y-365793D01*
X272571Y-365807D01*
X272579Y-365811D01*
X272634Y-365863D01*
X272682Y-365918D01*
X272720Y-365978D01*
X272749Y-366037D01*
X272771Y-366089D01*
X272786Y-366129D01*
X272790Y-366144D01*
X272793Y-366155D01*
X272797Y-366163D01*
Y-366166D01*
X272831Y-366103D01*
X272864Y-366052D01*
X272901Y-366007D01*
X272934Y-365970D01*
X272964Y-365941D01*
X272990Y-365918D01*
X273004Y-365907D01*
X273012Y-365904D01*
X273063Y-365874D01*
X273115Y-365852D01*
X273167Y-365833D01*
X273215Y-365822D01*
X273256Y-365815D01*
X273286Y-365811D01*
X273308D01*
X273315D01*
X273378Y-365815D01*
X273441Y-365826D01*
X273497Y-365841D01*
X273545Y-365859D01*
X273585Y-365878D01*
X273619Y-365893D01*
X273637Y-365904D01*
X273644Y-365907D01*
X273700Y-365944D01*
X273748Y-365989D01*
X273789Y-366033D01*
X273826Y-366077D01*
X273852Y-366114D01*
X273874Y-366148D01*
X273885Y-366170D01*
X273889Y-366174D01*
Y-366177D01*
X273918Y-366244D01*
X273940Y-366311D01*
X273959Y-366377D01*
X273970Y-366436D01*
X273977Y-366484D01*
X273981Y-366525D01*
Y-366618D01*
X273974Y-366670D01*
X273955Y-366769D01*
X273926Y-366855D01*
X273896Y-366929D01*
X273878Y-366962D01*
X273863Y-366988D01*
X273848Y-367014D01*
X273833Y-367032D01*
X273822Y-367047D01*
X273815Y-367058D01*
X273811Y-367065D01*
X273807Y-367069D01*
X273737Y-367139D01*
X273659Y-367195D01*
X273578Y-367239D01*
X273497Y-367276D01*
X273426Y-367299D01*
X273396Y-367310D01*
X273371Y-367317D01*
X273348Y-367321D01*
X273334Y-367324D01*
X273323Y-367328D01*
X273319D01*
X273263Y-367014D01*
X273345Y-366999D01*
X273415Y-366977D01*
X273474Y-366951D01*
X273522Y-366925D01*
X273559Y-366899D01*
X273585Y-366877D01*
X273604Y-366862D01*
X273607Y-366858D01*
X273644Y-366810D01*
X273674Y-366758D01*
X273692Y-366710D01*
X273707Y-366662D01*
X273715Y-366618D01*
X273722Y-366584D01*
Y-366555D01*
X273718Y-366488D01*
X273704Y-366429D01*
X273685Y-366377D01*
X273667Y-366333D01*
X273644Y-366300D01*
X273626Y-366274D01*
X273611Y-366255D01*
X273607Y-366251D01*
X273563Y-366211D01*
X273515Y-366181D01*
X273467Y-366163D01*
X273422Y-366148D01*
X273382Y-366140D01*
X273352Y-366133D01*
X273330D01*
X273326D01*
X273323D01*
X273282D01*
X273245Y-366140D01*
X273182Y-366159D01*
X273127Y-366185D01*
X273078Y-366214D01*
X273045Y-366244D01*
X273019Y-366270D01*
X273004Y-366288D01*
X273001Y-366292D01*
Y-366296D01*
X272967Y-366359D01*
X272941Y-366418D01*
X272923Y-366481D01*
X272912Y-366536D01*
X272904Y-366584D01*
X272897Y-366625D01*
Y-366673D01*
X272901Y-366688D01*
Y-366706D01*
X272623Y-366743D01*
X272634Y-366695D01*
X272642Y-366651D01*
X272649Y-366614D01*
X272653Y-366581D01*
X272657Y-366555D01*
Y-366522D01*
X272649Y-366444D01*
X272634Y-366373D01*
X272612Y-366311D01*
X272586Y-366259D01*
X272560Y-366218D01*
X272538Y-366189D01*
X272523Y-366170D01*
X272516Y-366163D01*
X272460Y-366114D01*
X272401Y-366077D01*
X272342Y-366052D01*
X272283Y-366037D01*
X272235Y-366026D01*
X272194Y-366022D01*
X272179Y-366018D01*
X272168D01*
X272161D01*
X272157D01*
X272076Y-366026D01*
X272002Y-366044D01*
X271939Y-366066D01*
X271883Y-366096D01*
X271839Y-366126D01*
X271806Y-366148D01*
X271783Y-366166D01*
X271776Y-366174D01*
X271724Y-366233D01*
X271687Y-366296D01*
X271661Y-366359D01*
X271643Y-366418D01*
X271632Y-366470D01*
X271628Y-366510D01*
X271624Y-366525D01*
Y-366547D01*
X271628Y-366614D01*
X271643Y-366677D01*
X271661Y-366732D01*
X271683Y-366777D01*
X271702Y-366814D01*
X271720Y-366843D01*
X271735Y-366858D01*
X271739Y-366866D01*
X271791Y-366910D01*
X271850Y-366947D01*
X271913Y-366980D01*
X271979Y-367006D01*
X272035Y-367025D01*
X272061Y-367032D01*
X272083Y-367036D01*
X272101Y-367039D01*
X272116Y-367043D01*
X272124Y-367047D01*
X272127D01*
X272087Y-367361D01*
X272028Y-367354D01*
X271972Y-367343D01*
X271868Y-367310D01*
X271780Y-367269D01*
X271743Y-367247D01*
X271706Y-367225D01*
X271672Y-367202D01*
X271646Y-367180D01*
X271621Y-367162D01*
X271602Y-367143D01*
X271587Y-367132D01*
X271576Y-367121D01*
X271569Y-367113D01*
X271565Y-367110D01*
X271532Y-367065D01*
X271498Y-367021D01*
X271473Y-366977D01*
X271450Y-366929D01*
X271413Y-366836D01*
X271391Y-366747D01*
X271384Y-366706D01*
X271376Y-366670D01*
X271373Y-366636D01*
X271369Y-366607D01*
X271365Y-366584D01*
Y-366551D01*
X271369Y-366481D01*
X271376Y-366418D01*
X271387Y-366355D01*
X271402Y-366296D01*
X271421Y-366240D01*
X271439Y-366192D01*
X271462Y-366144D01*
X271484Y-366103D01*
X271502Y-366063D01*
X271524Y-366029D01*
X271543Y-366000D01*
X271561Y-365978D01*
X271576Y-365959D01*
X271587Y-365944D01*
X271595Y-365937D01*
X271598Y-365933D01*
X271643Y-365889D01*
X271691Y-365852D01*
X271739Y-365819D01*
X271787Y-365789D01*
X271831Y-365767D01*
X271880Y-365744D01*
X271968Y-365715D01*
X272009Y-365707D01*
X272046Y-365700D01*
X272079Y-365693D01*
X272109Y-365689D01*
X272131Y-365685D01*
X272150D01*
X272161D01*
X272164D01*
X272253Y-365689D01*
D02*
G37*
G36*
X272342Y-367661D02*
X272405Y-367669D01*
X272468Y-367680D01*
X272523Y-367694D01*
X272575Y-367713D01*
X272627Y-367731D01*
X272671Y-367754D01*
X272712Y-367772D01*
X272749Y-367794D01*
X272782Y-367816D01*
X272808Y-367835D01*
X272834Y-367853D01*
X272853Y-367868D01*
X272864Y-367879D01*
X272871Y-367887D01*
X272875Y-367891D01*
X272916Y-367935D01*
X272953Y-367979D01*
X272982Y-368027D01*
X273008Y-368075D01*
X273034Y-368124D01*
X273052Y-368172D01*
X273078Y-368261D01*
X273089Y-368301D01*
X273097Y-368338D01*
X273101Y-368372D01*
X273104Y-368401D01*
X273108Y-368423D01*
Y-368505D01*
X273101Y-368549D01*
X273082Y-368638D01*
X273056Y-368719D01*
X273026Y-368793D01*
X272997Y-368852D01*
X272982Y-368878D01*
X272971Y-368901D01*
X272960Y-368919D01*
X272953Y-368930D01*
X272949Y-368938D01*
X272945Y-368941D01*
X273637Y-368804D01*
Y-367779D01*
X273937D01*
Y-369052D01*
X272620Y-369300D01*
X272579Y-369004D01*
X272620Y-368978D01*
X272653Y-368945D01*
X272686Y-368915D01*
X272712Y-368886D01*
X272730Y-368856D01*
X272749Y-368834D01*
X272756Y-368819D01*
X272760Y-368815D01*
X272782Y-368767D01*
X272801Y-368719D01*
X272812Y-368675D01*
X272823Y-368631D01*
X272827Y-368594D01*
X272831Y-368564D01*
Y-368494D01*
X272823Y-368449D01*
X272805Y-368372D01*
X272779Y-368305D01*
X272753Y-368246D01*
X272723Y-368201D01*
X272697Y-368168D01*
X272679Y-368149D01*
X272675Y-368142D01*
X272671D01*
X272608Y-368090D01*
X272542Y-368053D01*
X272471Y-368027D01*
X272401Y-368009D01*
X272342Y-367998D01*
X272316Y-367994D01*
X272294D01*
X272275Y-367990D01*
X272261D01*
X272253D01*
X272250D01*
X272198D01*
X272150Y-367998D01*
X272057Y-368016D01*
X271979Y-368042D01*
X271917Y-368068D01*
X271865Y-368098D01*
X271824Y-368124D01*
X271813Y-368135D01*
X271802Y-368142D01*
X271798Y-368146D01*
X271795Y-368149D01*
X271765Y-368179D01*
X271739Y-368209D01*
X271694Y-368275D01*
X271665Y-368338D01*
X271646Y-368401D01*
X271632Y-368453D01*
X271628Y-368497D01*
X271624Y-368512D01*
Y-368534D01*
X271628Y-368605D01*
X271643Y-368668D01*
X271661Y-368723D01*
X271683Y-368767D01*
X271706Y-368808D01*
X271724Y-368838D01*
X271739Y-368852D01*
X271743Y-368860D01*
X271795Y-368904D01*
X271850Y-368941D01*
X271913Y-368971D01*
X271968Y-368993D01*
X272024Y-369008D01*
X272065Y-369019D01*
X272083Y-369023D01*
X272094Y-369026D01*
X272101D01*
X272105D01*
X272079Y-369356D01*
X272020Y-369348D01*
X271965Y-369337D01*
X271861Y-369304D01*
X271772Y-369263D01*
X271732Y-369241D01*
X271698Y-369219D01*
X271665Y-369200D01*
X271635Y-369178D01*
X271613Y-369160D01*
X271595Y-369141D01*
X271580Y-369126D01*
X271565Y-369119D01*
X271561Y-369111D01*
X271558Y-369108D01*
X271524Y-369063D01*
X271495Y-369019D01*
X271469Y-368971D01*
X271447Y-368923D01*
X271413Y-368830D01*
X271391Y-368738D01*
X271380Y-368697D01*
X271376Y-368656D01*
X271373Y-368623D01*
X271369Y-368594D01*
X271365Y-368568D01*
Y-368534D01*
X271369Y-368457D01*
X271380Y-368383D01*
X271395Y-368312D01*
X271413Y-368249D01*
X271439Y-368190D01*
X271465Y-368135D01*
X271491Y-368083D01*
X271521Y-368039D01*
X271550Y-367998D01*
X271576Y-367961D01*
X271606Y-367931D01*
X271628Y-367905D01*
X271646Y-367887D01*
X271661Y-367872D01*
X271672Y-367865D01*
X271676Y-367861D01*
X271724Y-367824D01*
X271776Y-367794D01*
X271824Y-367765D01*
X271876Y-367742D01*
X271976Y-367705D01*
X272072Y-367683D01*
X272113Y-367676D01*
X272153Y-367669D01*
X272187Y-367665D01*
X272216Y-367661D01*
X272242Y-367657D01*
X272261D01*
X272272D01*
X272275D01*
X272342Y-367661D01*
D02*
G37*
G36*
X272305Y-369985D02*
X272246Y-370000D01*
X272190Y-370018D01*
X272139Y-370037D01*
X272091Y-370055D01*
X272046Y-370077D01*
X272009Y-370099D01*
X271972Y-370125D01*
X271939Y-370147D01*
X271909Y-370166D01*
X271887Y-370188D01*
X271865Y-370207D01*
X271846Y-370221D01*
X271835Y-370236D01*
X271824Y-370247D01*
X271820Y-370251D01*
X271817Y-370255D01*
X271787Y-370292D01*
X271765Y-370333D01*
X271724Y-370414D01*
X271694Y-370492D01*
X271676Y-370569D01*
X271661Y-370636D01*
X271657Y-370662D01*
Y-370688D01*
X271654Y-370710D01*
Y-370736D01*
X271657Y-370821D01*
X271672Y-370902D01*
X271691Y-370976D01*
X271713Y-371043D01*
X271735Y-371095D01*
X271746Y-371117D01*
X271754Y-371135D01*
X271761Y-371150D01*
X271769Y-371161D01*
X271772Y-371169D01*
Y-371172D01*
X271824Y-371243D01*
X271880Y-371302D01*
X271942Y-371354D01*
X272002Y-371394D01*
X272054Y-371428D01*
X272098Y-371450D01*
X272116Y-371457D01*
X272127Y-371465D01*
X272135Y-371468D01*
X272139D01*
X272235Y-371498D01*
X272331Y-371520D01*
X272427Y-371539D01*
X272516Y-371550D01*
X272557Y-371553D01*
X272594Y-371557D01*
X272627D01*
X272653Y-371561D01*
X272675D01*
X272694D01*
X272705D01*
X272708D01*
X272805Y-371557D01*
X272893Y-371550D01*
X272975Y-371535D01*
X273049Y-371520D01*
X273112Y-371509D01*
X273138Y-371502D01*
X273160Y-371494D01*
X273178Y-371491D01*
X273189Y-371487D01*
X273197Y-371483D01*
X273200D01*
X273286Y-371446D01*
X273363Y-371406D01*
X273426Y-371361D01*
X273482Y-371313D01*
X273526Y-371272D01*
X273556Y-371239D01*
X273574Y-371213D01*
X273582Y-371209D01*
Y-371206D01*
X273630Y-371128D01*
X273667Y-371043D01*
X273692Y-370961D01*
X273707Y-370884D01*
X273718Y-370813D01*
X273722Y-370784D01*
Y-370758D01*
X273726Y-370740D01*
Y-370710D01*
X273722Y-370617D01*
X273707Y-370532D01*
X273685Y-370462D01*
X273663Y-370399D01*
X273637Y-370351D01*
X273619Y-370314D01*
X273604Y-370292D01*
X273596Y-370284D01*
X273541Y-370225D01*
X273478Y-370170D01*
X273411Y-370125D01*
X273345Y-370088D01*
X273286Y-370059D01*
X273256Y-370048D01*
X273234Y-370040D01*
X273215Y-370033D01*
X273200Y-370025D01*
X273193Y-370022D01*
X273189D01*
X273267Y-369689D01*
X273334Y-369711D01*
X273393Y-369733D01*
X273448Y-369763D01*
X273504Y-369789D01*
X273552Y-369818D01*
X273596Y-369851D01*
X273641Y-369881D01*
X273678Y-369911D01*
X273707Y-369940D01*
X273737Y-369966D01*
X273763Y-369992D01*
X273781Y-370011D01*
X273800Y-370029D01*
X273811Y-370044D01*
X273815Y-370051D01*
X273818Y-370055D01*
X273852Y-370107D01*
X273885Y-370159D01*
X273911Y-370210D01*
X273933Y-370266D01*
X273966Y-370377D01*
X273989Y-370477D01*
X274000Y-370525D01*
X274003Y-370566D01*
X274007Y-370606D01*
X274011Y-370640D01*
X274014Y-370666D01*
Y-370703D01*
X274007Y-370825D01*
X273989Y-370943D01*
X273966Y-371047D01*
X273952Y-371095D01*
X273937Y-371139D01*
X273922Y-371180D01*
X273907Y-371217D01*
X273896Y-371246D01*
X273885Y-371276D01*
X273874Y-371294D01*
X273866Y-371309D01*
X273863Y-371320D01*
X273859Y-371324D01*
X273796Y-371424D01*
X273722Y-371509D01*
X273648Y-371583D01*
X273574Y-371646D01*
X273507Y-371694D01*
X273478Y-371713D01*
X273452Y-371727D01*
X273434Y-371742D01*
X273419Y-371750D01*
X273408Y-371753D01*
X273404Y-371757D01*
X273289Y-371809D01*
X273171Y-371846D01*
X273052Y-371872D01*
X272945Y-371890D01*
X272897Y-371898D01*
X272849Y-371901D01*
X272812Y-371905D01*
X272775D01*
X272749Y-371909D01*
X272727D01*
X272712D01*
X272708D01*
X272575Y-371901D01*
X272446Y-371886D01*
X272331Y-371868D01*
X272275Y-371853D01*
X272227Y-371842D01*
X272183Y-371831D01*
X272142Y-371816D01*
X272105Y-371805D01*
X272076Y-371798D01*
X272054Y-371787D01*
X272035Y-371783D01*
X272024Y-371776D01*
X272020D01*
X271909Y-371720D01*
X271809Y-371657D01*
X271724Y-371590D01*
X271691Y-371557D01*
X271657Y-371528D01*
X271628Y-371498D01*
X271602Y-371468D01*
X271580Y-371443D01*
X271565Y-371420D01*
X271550Y-371406D01*
X271539Y-371391D01*
X271535Y-371383D01*
X271532Y-371380D01*
X271502Y-371328D01*
X271476Y-371276D01*
X271436Y-371165D01*
X271406Y-371054D01*
X271387Y-370947D01*
X271380Y-370895D01*
X271373Y-370850D01*
X271369Y-370810D01*
Y-370777D01*
X271365Y-370747D01*
Y-370706D01*
X271369Y-370632D01*
X271376Y-370562D01*
X271384Y-370495D01*
X271398Y-370432D01*
X271417Y-370373D01*
X271436Y-370318D01*
X271454Y-370266D01*
X271476Y-370218D01*
X271495Y-370177D01*
X271513Y-370136D01*
X271532Y-370107D01*
X271550Y-370077D01*
X271565Y-370059D01*
X271572Y-370040D01*
X271580Y-370033D01*
X271584Y-370029D01*
X271628Y-369977D01*
X271672Y-369933D01*
X271724Y-369892D01*
X271776Y-369851D01*
X271880Y-369785D01*
X271983Y-369733D01*
X272031Y-369711D01*
X272076Y-369692D01*
X272116Y-369678D01*
X272150Y-369667D01*
X272179Y-369655D01*
X272201Y-369648D01*
X272216Y-369644D01*
X272220D01*
X272305Y-369985D01*
D02*
G37*
G36*
X206064Y-377842D02*
X207721D01*
Y-378097D01*
X206064Y-379270D01*
X205775D01*
Y-378156D01*
X205161D01*
Y-377842D01*
X205775D01*
Y-377494D01*
X206064D01*
Y-377842D01*
D02*
G37*
G36*
Y-379832D02*
X207721D01*
Y-380088D01*
X206064Y-381260D01*
X205775D01*
Y-380147D01*
X205161D01*
Y-379832D01*
X205775D01*
Y-379485D01*
X206064D01*
Y-379832D01*
D02*
G37*
G36*
X206056Y-381782D02*
X205997Y-381797D01*
X205941Y-381816D01*
X205890Y-381834D01*
X205841Y-381853D01*
X205797Y-381875D01*
X205760Y-381897D01*
X205723Y-381923D01*
X205690Y-381945D01*
X205660Y-381963D01*
X205638Y-381986D01*
X205616Y-382004D01*
X205597Y-382019D01*
X205586Y-382034D01*
X205575Y-382045D01*
X205571Y-382049D01*
X205568Y-382052D01*
X205538Y-382089D01*
X205516Y-382130D01*
X205475Y-382211D01*
X205446Y-382289D01*
X205427Y-382367D01*
X205412Y-382433D01*
X205409Y-382459D01*
Y-382485D01*
X205405Y-382507D01*
Y-382533D01*
X205409Y-382618D01*
X205423Y-382700D01*
X205442Y-382774D01*
X205464Y-382840D01*
X205486Y-382892D01*
X205497Y-382914D01*
X205505Y-382933D01*
X205512Y-382948D01*
X205520Y-382959D01*
X205523Y-382966D01*
Y-382970D01*
X205575Y-383040D01*
X205631Y-383099D01*
X205694Y-383151D01*
X205753Y-383192D01*
X205804Y-383225D01*
X205849Y-383247D01*
X205867Y-383255D01*
X205878Y-383262D01*
X205886Y-383266D01*
X205890D01*
X205986Y-383295D01*
X206082Y-383318D01*
X206178Y-383336D01*
X206267Y-383347D01*
X206308Y-383351D01*
X206345Y-383355D01*
X206378D01*
X206404Y-383358D01*
X206426D01*
X206445D01*
X206456D01*
X206459D01*
X206556Y-383355D01*
X206644Y-383347D01*
X206726Y-383332D01*
X206800Y-383318D01*
X206863Y-383307D01*
X206889Y-383299D01*
X206911Y-383292D01*
X206929Y-383288D01*
X206940Y-383284D01*
X206948Y-383281D01*
X206951D01*
X207037Y-383244D01*
X207114Y-383203D01*
X207177Y-383159D01*
X207233Y-383110D01*
X207277Y-383070D01*
X207307Y-383036D01*
X207325Y-383011D01*
X207333Y-383007D01*
Y-383003D01*
X207381Y-382926D01*
X207418Y-382840D01*
X207444Y-382759D01*
X207458Y-382681D01*
X207470Y-382611D01*
X207473Y-382581D01*
Y-382556D01*
X207477Y-382537D01*
Y-382507D01*
X207473Y-382415D01*
X207458Y-382330D01*
X207436Y-382259D01*
X207414Y-382197D01*
X207388Y-382149D01*
X207370Y-382112D01*
X207355Y-382089D01*
X207347Y-382082D01*
X207292Y-382023D01*
X207229Y-381967D01*
X207162Y-381923D01*
X207096Y-381886D01*
X207037Y-381856D01*
X207007Y-381845D01*
X206985Y-381838D01*
X206966Y-381830D01*
X206951Y-381823D01*
X206944Y-381819D01*
X206940D01*
X207018Y-381486D01*
X207085Y-381508D01*
X207144Y-381531D01*
X207199Y-381560D01*
X207255Y-381586D01*
X207303Y-381616D01*
X207347Y-381649D01*
X207392Y-381679D01*
X207429Y-381708D01*
X207458Y-381738D01*
X207488Y-381764D01*
X207514Y-381790D01*
X207532Y-381808D01*
X207551Y-381827D01*
X207562Y-381841D01*
X207566Y-381849D01*
X207569Y-381853D01*
X207603Y-381904D01*
X207636Y-381956D01*
X207662Y-382008D01*
X207684Y-382063D01*
X207717Y-382174D01*
X207740Y-382274D01*
X207751Y-382322D01*
X207754Y-382363D01*
X207758Y-382404D01*
X207762Y-382437D01*
X207766Y-382463D01*
Y-382500D01*
X207758Y-382622D01*
X207740Y-382740D01*
X207717Y-382844D01*
X207703Y-382892D01*
X207688Y-382937D01*
X207673Y-382977D01*
X207658Y-383014D01*
X207647Y-383044D01*
X207636Y-383073D01*
X207625Y-383092D01*
X207617Y-383107D01*
X207614Y-383118D01*
X207610Y-383122D01*
X207547Y-383222D01*
X207473Y-383307D01*
X207399Y-383381D01*
X207325Y-383443D01*
X207259Y-383492D01*
X207229Y-383510D01*
X207203Y-383525D01*
X207185Y-383540D01*
X207170Y-383547D01*
X207159Y-383551D01*
X207155Y-383555D01*
X207040Y-383606D01*
X206922Y-383643D01*
X206803Y-383669D01*
X206696Y-383688D01*
X206648Y-383695D01*
X206600Y-383699D01*
X206563Y-383702D01*
X206526D01*
X206500Y-383706D01*
X206478D01*
X206463D01*
X206459D01*
X206326Y-383699D01*
X206197Y-383684D01*
X206082Y-383665D01*
X206027Y-383651D01*
X205978Y-383640D01*
X205934Y-383629D01*
X205893Y-383614D01*
X205856Y-383603D01*
X205827Y-383595D01*
X205804Y-383584D01*
X205786Y-383580D01*
X205775Y-383573D01*
X205771D01*
X205660Y-383518D01*
X205560Y-383455D01*
X205475Y-383388D01*
X205442Y-383355D01*
X205409Y-383325D01*
X205379Y-383295D01*
X205353Y-383266D01*
X205331Y-383240D01*
X205316Y-383218D01*
X205301Y-383203D01*
X205290Y-383188D01*
X205287Y-383181D01*
X205283Y-383177D01*
X205253Y-383125D01*
X205227Y-383073D01*
X205187Y-382962D01*
X205157Y-382852D01*
X205138Y-382744D01*
X205131Y-382692D01*
X205124Y-382648D01*
X205120Y-382607D01*
Y-382574D01*
X205116Y-382544D01*
Y-382504D01*
X205120Y-382430D01*
X205127Y-382359D01*
X205135Y-382293D01*
X205150Y-382230D01*
X205168Y-382171D01*
X205187Y-382115D01*
X205205Y-382063D01*
X205227Y-382015D01*
X205246Y-381975D01*
X205264Y-381934D01*
X205283Y-381904D01*
X205301Y-381875D01*
X205316Y-381856D01*
X205324Y-381838D01*
X205331Y-381830D01*
X205335Y-381827D01*
X205379Y-381775D01*
X205423Y-381730D01*
X205475Y-381690D01*
X205527Y-381649D01*
X205631Y-381582D01*
X205734Y-381531D01*
X205782Y-381508D01*
X205827Y-381490D01*
X205867Y-381475D01*
X205901Y-381464D01*
X205930Y-381453D01*
X205953Y-381446D01*
X205967Y-381442D01*
X205971D01*
X206056Y-381782D01*
D02*
G37*
G36*
X209342Y-365698D02*
X209405Y-365706D01*
X209468Y-365717D01*
X209523Y-365732D01*
X209575Y-365750D01*
X209627Y-365769D01*
X209671Y-365791D01*
X209712Y-365809D01*
X209749Y-365831D01*
X209782Y-365854D01*
X209808Y-365872D01*
X209834Y-365891D01*
X209853Y-365905D01*
X209864Y-365917D01*
X209871Y-365924D01*
X209875Y-365928D01*
X209915Y-365972D01*
X209952Y-366017D01*
X209982Y-366065D01*
X210008Y-366113D01*
X210034Y-366161D01*
X210052Y-366209D01*
X210078Y-366298D01*
X210089Y-366338D01*
X210097Y-366375D01*
X210101Y-366409D01*
X210104Y-366438D01*
X210108Y-366460D01*
Y-366542D01*
X210101Y-366586D01*
X210082Y-366675D01*
X210056Y-366757D01*
X210027Y-366830D01*
X209997Y-366890D01*
X209982Y-366916D01*
X209971Y-366938D01*
X209960Y-366956D01*
X209952Y-366967D01*
X209949Y-366975D01*
X209945Y-366979D01*
X210637Y-366842D01*
Y-365817D01*
X210937D01*
Y-367090D01*
X209619Y-367337D01*
X209579Y-367041D01*
X209619Y-367016D01*
X209653Y-366982D01*
X209686Y-366953D01*
X209712Y-366923D01*
X209731Y-366893D01*
X209749Y-366871D01*
X209756Y-366856D01*
X209760Y-366853D01*
X209782Y-366805D01*
X209801Y-366757D01*
X209812Y-366712D01*
X209823Y-366668D01*
X209827Y-366631D01*
X209830Y-366601D01*
Y-366531D01*
X209823Y-366486D01*
X209805Y-366409D01*
X209779Y-366342D01*
X209753Y-366283D01*
X209723Y-366238D01*
X209697Y-366205D01*
X209679Y-366187D01*
X209675Y-366179D01*
X209671D01*
X209608Y-366127D01*
X209542Y-366090D01*
X209472Y-366065D01*
X209401Y-366046D01*
X209342Y-366035D01*
X209316Y-366031D01*
X209294D01*
X209275Y-366028D01*
X209261D01*
X209253D01*
X209249D01*
X209198D01*
X209150Y-366035D01*
X209057Y-366054D01*
X208979Y-366079D01*
X208916Y-366105D01*
X208865Y-366135D01*
X208824Y-366161D01*
X208813Y-366172D01*
X208802Y-366179D01*
X208798Y-366183D01*
X208794Y-366187D01*
X208765Y-366216D01*
X208739Y-366246D01*
X208695Y-366313D01*
X208665Y-366375D01*
X208646Y-366438D01*
X208632Y-366490D01*
X208628Y-366534D01*
X208624Y-366549D01*
Y-366571D01*
X208628Y-366642D01*
X208643Y-366705D01*
X208661Y-366760D01*
X208683Y-366805D01*
X208706Y-366845D01*
X208724Y-366875D01*
X208739Y-366890D01*
X208743Y-366897D01*
X208794Y-366941D01*
X208850Y-366979D01*
X208913Y-367008D01*
X208968Y-367030D01*
X209024Y-367045D01*
X209065Y-367056D01*
X209083Y-367060D01*
X209094Y-367064D01*
X209102D01*
X209105D01*
X209079Y-367393D01*
X209020Y-367386D01*
X208965Y-367374D01*
X208861Y-367341D01*
X208772Y-367300D01*
X208732Y-367278D01*
X208698Y-367256D01*
X208665Y-367237D01*
X208635Y-367215D01*
X208613Y-367197D01*
X208595Y-367178D01*
X208580Y-367163D01*
X208565Y-367156D01*
X208561Y-367149D01*
X208558Y-367145D01*
X208524Y-367101D01*
X208495Y-367056D01*
X208469Y-367008D01*
X208447Y-366960D01*
X208413Y-366867D01*
X208391Y-366775D01*
X208380Y-366734D01*
X208376Y-366694D01*
X208373Y-366660D01*
X208369Y-366631D01*
X208365Y-366605D01*
Y-366571D01*
X208369Y-366494D01*
X208380Y-366420D01*
X208395Y-366350D01*
X208413Y-366287D01*
X208439Y-366227D01*
X208465Y-366172D01*
X208491Y-366120D01*
X208521Y-366076D01*
X208550Y-366035D01*
X208576Y-365998D01*
X208606Y-365968D01*
X208628Y-365943D01*
X208646Y-365924D01*
X208661Y-365909D01*
X208672Y-365902D01*
X208676Y-365898D01*
X208724Y-365861D01*
X208776Y-365831D01*
X208824Y-365802D01*
X208876Y-365780D01*
X208976Y-365743D01*
X209072Y-365721D01*
X209113Y-365713D01*
X209153Y-365706D01*
X209187Y-365702D01*
X209216Y-365698D01*
X209242Y-365695D01*
X209261D01*
X209272D01*
X209275D01*
X209342Y-365698D01*
D02*
G37*
G36*
X209312Y-368063D02*
X210970D01*
Y-368318D01*
X209312Y-369491D01*
X209024D01*
Y-368377D01*
X208410D01*
Y-368063D01*
X209024D01*
Y-367715D01*
X209312D01*
Y-368063D01*
D02*
G37*
G36*
X209305Y-370012D02*
X209246Y-370027D01*
X209190Y-370046D01*
X209138Y-370064D01*
X209090Y-370083D01*
X209046Y-370105D01*
X209009Y-370127D01*
X208972Y-370153D01*
X208939Y-370175D01*
X208909Y-370194D01*
X208887Y-370216D01*
X208865Y-370234D01*
X208846Y-370249D01*
X208835Y-370264D01*
X208824Y-370275D01*
X208820Y-370279D01*
X208817Y-370283D01*
X208787Y-370320D01*
X208765Y-370360D01*
X208724Y-370442D01*
X208695Y-370519D01*
X208676Y-370597D01*
X208661Y-370664D01*
X208658Y-370690D01*
Y-370715D01*
X208654Y-370738D01*
Y-370764D01*
X208658Y-370849D01*
X208672Y-370930D01*
X208691Y-371004D01*
X208713Y-371071D01*
X208735Y-371123D01*
X208746Y-371145D01*
X208754Y-371163D01*
X208761Y-371178D01*
X208769Y-371189D01*
X208772Y-371197D01*
Y-371200D01*
X208824Y-371270D01*
X208879Y-371330D01*
X208942Y-371381D01*
X209002Y-371422D01*
X209053Y-371456D01*
X209098Y-371478D01*
X209116Y-371485D01*
X209127Y-371493D01*
X209135Y-371496D01*
X209138D01*
X209235Y-371526D01*
X209331Y-371548D01*
X209427Y-371567D01*
X209516Y-371578D01*
X209557Y-371581D01*
X209594Y-371585D01*
X209627D01*
X209653Y-371589D01*
X209675D01*
X209694D01*
X209705D01*
X209708D01*
X209805Y-371585D01*
X209893Y-371578D01*
X209975Y-371563D01*
X210049Y-371548D01*
X210112Y-371537D01*
X210138Y-371530D01*
X210160Y-371522D01*
X210178Y-371518D01*
X210189Y-371515D01*
X210197Y-371511D01*
X210200D01*
X210285Y-371474D01*
X210363Y-371433D01*
X210426Y-371389D01*
X210482Y-371341D01*
X210526Y-371300D01*
X210556Y-371267D01*
X210574Y-371241D01*
X210581Y-371237D01*
Y-371234D01*
X210630Y-371156D01*
X210667Y-371071D01*
X210693Y-370989D01*
X210707Y-370912D01*
X210718Y-370841D01*
X210722Y-370812D01*
Y-370786D01*
X210726Y-370767D01*
Y-370738D01*
X210722Y-370645D01*
X210707Y-370560D01*
X210685Y-370490D01*
X210663Y-370427D01*
X210637Y-370379D01*
X210618Y-370342D01*
X210604Y-370320D01*
X210596Y-370312D01*
X210541Y-370253D01*
X210478Y-370198D01*
X210411Y-370153D01*
X210345Y-370116D01*
X210285Y-370087D01*
X210256Y-370075D01*
X210234Y-370068D01*
X210215Y-370061D01*
X210200Y-370053D01*
X210193Y-370050D01*
X210189D01*
X210267Y-369717D01*
X210334Y-369739D01*
X210393Y-369761D01*
X210448Y-369791D01*
X210504Y-369816D01*
X210552Y-369846D01*
X210596Y-369879D01*
X210641Y-369909D01*
X210678Y-369938D01*
X210707Y-369968D01*
X210737Y-369994D01*
X210763Y-370020D01*
X210781Y-370038D01*
X210800Y-370057D01*
X210811Y-370072D01*
X210815Y-370079D01*
X210818Y-370083D01*
X210852Y-370135D01*
X210885Y-370186D01*
X210911Y-370238D01*
X210933Y-370294D01*
X210966Y-370405D01*
X210988Y-370505D01*
X211000Y-370553D01*
X211003Y-370593D01*
X211007Y-370634D01*
X211011Y-370667D01*
X211014Y-370693D01*
Y-370730D01*
X211007Y-370852D01*
X210988Y-370971D01*
X210966Y-371074D01*
X210951Y-371123D01*
X210937Y-371167D01*
X210922Y-371208D01*
X210907Y-371245D01*
X210896Y-371274D01*
X210885Y-371304D01*
X210874Y-371322D01*
X210866Y-371337D01*
X210863Y-371348D01*
X210859Y-371352D01*
X210796Y-371452D01*
X210722Y-371537D01*
X210648Y-371611D01*
X210574Y-371674D01*
X210507Y-371722D01*
X210478Y-371740D01*
X210452Y-371755D01*
X210434Y-371770D01*
X210419Y-371777D01*
X210408Y-371781D01*
X210404Y-371785D01*
X210289Y-371837D01*
X210171Y-371874D01*
X210052Y-371900D01*
X209945Y-371918D01*
X209897Y-371925D01*
X209849Y-371929D01*
X209812Y-371933D01*
X209775D01*
X209749Y-371936D01*
X209727D01*
X209712D01*
X209708D01*
X209575Y-371929D01*
X209446Y-371914D01*
X209331Y-371896D01*
X209275Y-371881D01*
X209227Y-371870D01*
X209183Y-371859D01*
X209142Y-371844D01*
X209105Y-371833D01*
X209076Y-371826D01*
X209053Y-371814D01*
X209035Y-371811D01*
X209024Y-371803D01*
X209020D01*
X208909Y-371748D01*
X208809Y-371685D01*
X208724Y-371618D01*
X208691Y-371585D01*
X208658Y-371555D01*
X208628Y-371526D01*
X208602Y-371496D01*
X208580Y-371470D01*
X208565Y-371448D01*
X208550Y-371433D01*
X208539Y-371418D01*
X208535Y-371411D01*
X208532Y-371407D01*
X208502Y-371356D01*
X208476Y-371304D01*
X208436Y-371193D01*
X208406Y-371082D01*
X208387Y-370974D01*
X208380Y-370923D01*
X208373Y-370878D01*
X208369Y-370838D01*
Y-370804D01*
X208365Y-370775D01*
Y-370734D01*
X208369Y-370660D01*
X208376Y-370590D01*
X208384Y-370523D01*
X208399Y-370460D01*
X208417Y-370401D01*
X208436Y-370345D01*
X208454Y-370294D01*
X208476Y-370246D01*
X208495Y-370205D01*
X208513Y-370164D01*
X208532Y-370135D01*
X208550Y-370105D01*
X208565Y-370087D01*
X208572Y-370068D01*
X208580Y-370061D01*
X208583Y-370057D01*
X208628Y-370005D01*
X208672Y-369961D01*
X208724Y-369920D01*
X208776Y-369879D01*
X208879Y-369813D01*
X208983Y-369761D01*
X209031Y-369739D01*
X209076Y-369720D01*
X209116Y-369705D01*
X209150Y-369694D01*
X209179Y-369683D01*
X209201Y-369676D01*
X209216Y-369672D01*
X209220D01*
X209305Y-370012D01*
D02*
G37*
G36*
X217956Y-377492D02*
X218019Y-377499D01*
X218082Y-377510D01*
X218137Y-377522D01*
X218189Y-377540D01*
X218241Y-377559D01*
X218285Y-377577D01*
X218326Y-377599D01*
X218363Y-377622D01*
X218396Y-377640D01*
X218422Y-377659D01*
X218448Y-377677D01*
X218467Y-377688D01*
X218478Y-377699D01*
X218485Y-377707D01*
X218489Y-377710D01*
X218530Y-377751D01*
X218567Y-377795D01*
X218596Y-377843D01*
X218622Y-377888D01*
X218648Y-377932D01*
X218667Y-377977D01*
X218692Y-378062D01*
X218704Y-378099D01*
X218711Y-378136D01*
X218715Y-378165D01*
X218718Y-378195D01*
X218722Y-378217D01*
Y-378247D01*
X218718Y-378313D01*
X218707Y-378376D01*
X218696Y-378435D01*
X218681Y-378487D01*
X218663Y-378532D01*
X218652Y-378565D01*
X218641Y-378587D01*
X218637Y-378591D01*
Y-378595D01*
X218600Y-378654D01*
X218559Y-378706D01*
X218519Y-378754D01*
X218474Y-378791D01*
X218437Y-378824D01*
X218408Y-378850D01*
X218385Y-378865D01*
X218382Y-378868D01*
X218448D01*
X218515Y-378865D01*
X218574Y-378861D01*
X218633Y-378854D01*
X218685Y-378850D01*
X218733Y-378842D01*
X218778Y-378835D01*
X218818Y-378824D01*
X218855Y-378817D01*
X218885Y-378809D01*
X218911Y-378802D01*
X218933Y-378798D01*
X218948Y-378791D01*
X218959Y-378787D01*
X218966Y-378783D01*
X218970D01*
X219044Y-378746D01*
X219111Y-378709D01*
X219162Y-378669D01*
X219207Y-378632D01*
X219244Y-378598D01*
X219270Y-378572D01*
X219285Y-378554D01*
X219288Y-378547D01*
X219318Y-378502D01*
X219336Y-378458D01*
X219351Y-378413D01*
X219362Y-378369D01*
X219370Y-378336D01*
X219373Y-378306D01*
Y-378280D01*
X219366Y-378214D01*
X219351Y-378151D01*
X219329Y-378099D01*
X219307Y-378051D01*
X219281Y-378014D01*
X219259Y-377988D01*
X219244Y-377973D01*
X219236Y-377966D01*
X219203Y-377940D01*
X219162Y-377914D01*
X219118Y-377892D01*
X219074Y-377877D01*
X219033Y-377862D01*
X219000Y-377851D01*
X218977Y-377847D01*
X218974Y-377843D01*
X218970D01*
X218996Y-377529D01*
X219099Y-377551D01*
X219192Y-377585D01*
X219273Y-377622D01*
X219340Y-377662D01*
X219392Y-377703D01*
X219414Y-377718D01*
X219432Y-377736D01*
X219444Y-377747D01*
X219455Y-377758D01*
X219458Y-377762D01*
X219462Y-377766D01*
X219492Y-377803D01*
X219517Y-377843D01*
X219562Y-377925D01*
X219592Y-378006D01*
X219610Y-378084D01*
X219625Y-378154D01*
X219629Y-378184D01*
Y-378210D01*
X219632Y-378232D01*
Y-378262D01*
X219629Y-378336D01*
X219621Y-378406D01*
X219606Y-378472D01*
X219588Y-378535D01*
X219562Y-378591D01*
X219540Y-378646D01*
X219510Y-378695D01*
X219484Y-378739D01*
X219458Y-378776D01*
X219429Y-378813D01*
X219407Y-378842D01*
X219384Y-378865D01*
X219362Y-378883D01*
X219347Y-378898D01*
X219340Y-378905D01*
X219336Y-378909D01*
X219270Y-378957D01*
X219192Y-378998D01*
X219111Y-379035D01*
X219025Y-379068D01*
X218937Y-379094D01*
X218848Y-379116D01*
X218755Y-379135D01*
X218670Y-379150D01*
X218585Y-379161D01*
X218508Y-379168D01*
X218437Y-379175D01*
X218378Y-379179D01*
X218326D01*
X218289Y-379183D01*
X218274D01*
X218263D01*
X218260D01*
X218256D01*
X218137Y-379179D01*
X218026Y-379172D01*
X217923Y-379161D01*
X217827Y-379142D01*
X217742Y-379124D01*
X217664Y-379105D01*
X217594Y-379083D01*
X217531Y-379057D01*
X217479Y-379035D01*
X217431Y-379013D01*
X217394Y-378994D01*
X217360Y-378972D01*
X217335Y-378957D01*
X217320Y-378946D01*
X217309Y-378939D01*
X217305Y-378935D01*
X217253Y-378887D01*
X217209Y-378835D01*
X217172Y-378783D01*
X217139Y-378731D01*
X217109Y-378676D01*
X217087Y-378624D01*
X217068Y-378572D01*
X217053Y-378521D01*
X217042Y-378476D01*
X217031Y-378432D01*
X217024Y-378395D01*
X217020Y-378362D01*
Y-378332D01*
X217016Y-378313D01*
Y-378295D01*
X217020Y-378210D01*
X217035Y-378132D01*
X217050Y-378062D01*
X217072Y-377999D01*
X217090Y-377951D01*
X217109Y-377914D01*
X217113Y-377899D01*
X217120Y-377888D01*
X217124Y-377884D01*
Y-377881D01*
X217168Y-377818D01*
X217220Y-377758D01*
X217272Y-377710D01*
X217323Y-377670D01*
X217372Y-377636D01*
X217409Y-377614D01*
X217423Y-377607D01*
X217435Y-377599D01*
X217438Y-377596D01*
X217442D01*
X217519Y-377559D01*
X217601Y-377533D01*
X217675Y-377514D01*
X217745Y-377503D01*
X217804Y-377492D01*
X217827D01*
X217849Y-377488D01*
X217867D01*
X217879D01*
X217886D01*
X217890D01*
X217956Y-377492D01*
D02*
G37*
G36*
X217964Y-379838D02*
X219621D01*
Y-380093D01*
X217964Y-381266D01*
X217675D01*
Y-380152D01*
X217061D01*
Y-379838D01*
X217675D01*
Y-379490D01*
X217964D01*
Y-379838D01*
D02*
G37*
G36*
X217956Y-381788D02*
X217897Y-381803D01*
X217841Y-381821D01*
X217790Y-381839D01*
X217742Y-381858D01*
X217697Y-381880D01*
X217660Y-381902D01*
X217623Y-381928D01*
X217590Y-381950D01*
X217560Y-381969D01*
X217538Y-381991D01*
X217516Y-382010D01*
X217497Y-382025D01*
X217486Y-382039D01*
X217475Y-382050D01*
X217472Y-382054D01*
X217468Y-382058D01*
X217438Y-382095D01*
X217416Y-382136D01*
X217375Y-382217D01*
X217346Y-382295D01*
X217327Y-382372D01*
X217312Y-382439D01*
X217309Y-382465D01*
Y-382491D01*
X217305Y-382513D01*
Y-382539D01*
X217309Y-382624D01*
X217323Y-382705D01*
X217342Y-382779D01*
X217364Y-382846D01*
X217386Y-382898D01*
X217397Y-382920D01*
X217405Y-382938D01*
X217412Y-382953D01*
X217420Y-382964D01*
X217423Y-382972D01*
Y-382975D01*
X217475Y-383046D01*
X217531Y-383105D01*
X217594Y-383157D01*
X217653Y-383197D01*
X217705Y-383231D01*
X217749Y-383253D01*
X217768Y-383260D01*
X217778Y-383268D01*
X217786Y-383271D01*
X217790D01*
X217886Y-383301D01*
X217982Y-383323D01*
X218078Y-383342D01*
X218167Y-383353D01*
X218208Y-383356D01*
X218245Y-383360D01*
X218278D01*
X218304Y-383364D01*
X218326D01*
X218345D01*
X218356D01*
X218359D01*
X218456Y-383360D01*
X218545Y-383353D01*
X218626Y-383338D01*
X218700Y-383323D01*
X218763Y-383312D01*
X218789Y-383305D01*
X218811Y-383297D01*
X218829Y-383294D01*
X218841Y-383290D01*
X218848Y-383286D01*
X218851D01*
X218937Y-383249D01*
X219014Y-383208D01*
X219077Y-383164D01*
X219133Y-383116D01*
X219177Y-383075D01*
X219207Y-383042D01*
X219225Y-383016D01*
X219233Y-383012D01*
Y-383009D01*
X219281Y-382931D01*
X219318Y-382846D01*
X219344Y-382765D01*
X219358Y-382687D01*
X219370Y-382616D01*
X219373Y-382587D01*
Y-382561D01*
X219377Y-382542D01*
Y-382513D01*
X219373Y-382420D01*
X219358Y-382335D01*
X219336Y-382265D01*
X219314Y-382202D01*
X219288Y-382154D01*
X219270Y-382117D01*
X219255Y-382095D01*
X219247Y-382087D01*
X219192Y-382028D01*
X219129Y-381973D01*
X219062Y-381928D01*
X218996Y-381891D01*
X218937Y-381862D01*
X218907Y-381851D01*
X218885Y-381843D01*
X218866Y-381836D01*
X218851Y-381828D01*
X218844Y-381825D01*
X218841D01*
X218918Y-381492D01*
X218985Y-381514D01*
X219044Y-381536D01*
X219099Y-381566D01*
X219155Y-381592D01*
X219203Y-381621D01*
X219247Y-381655D01*
X219292Y-381684D01*
X219329Y-381714D01*
X219358Y-381743D01*
X219388Y-381769D01*
X219414Y-381795D01*
X219432Y-381814D01*
X219451Y-381832D01*
X219462Y-381847D01*
X219466Y-381854D01*
X219469Y-381858D01*
X219503Y-381910D01*
X219536Y-381962D01*
X219562Y-382013D01*
X219584Y-382069D01*
X219618Y-382180D01*
X219640Y-382280D01*
X219651Y-382328D01*
X219654Y-382369D01*
X219658Y-382409D01*
X219662Y-382443D01*
X219666Y-382469D01*
Y-382505D01*
X219658Y-382628D01*
X219640Y-382746D01*
X219618Y-382850D01*
X219603Y-382898D01*
X219588Y-382942D01*
X219573Y-382983D01*
X219558Y-383020D01*
X219547Y-383049D01*
X219536Y-383079D01*
X219525Y-383098D01*
X219517Y-383112D01*
X219514Y-383123D01*
X219510Y-383127D01*
X219447Y-383227D01*
X219373Y-383312D01*
X219299Y-383386D01*
X219225Y-383449D01*
X219159Y-383497D01*
X219129Y-383516D01*
X219103Y-383530D01*
X219085Y-383545D01*
X219070Y-383553D01*
X219059Y-383556D01*
X219055Y-383560D01*
X218940Y-383612D01*
X218822Y-383649D01*
X218704Y-383675D01*
X218596Y-383693D01*
X218548Y-383701D01*
X218500Y-383704D01*
X218463Y-383708D01*
X218426D01*
X218400Y-383712D01*
X218378D01*
X218363D01*
X218359D01*
X218226Y-383704D01*
X218097Y-383689D01*
X217982Y-383671D01*
X217927Y-383656D01*
X217879Y-383645D01*
X217834Y-383634D01*
X217793Y-383619D01*
X217756Y-383608D01*
X217727Y-383601D01*
X217705Y-383590D01*
X217686Y-383586D01*
X217675Y-383578D01*
X217671D01*
X217560Y-383523D01*
X217460Y-383460D01*
X217375Y-383394D01*
X217342Y-383360D01*
X217309Y-383331D01*
X217279Y-383301D01*
X217253Y-383271D01*
X217231Y-383245D01*
X217216Y-383223D01*
X217201Y-383208D01*
X217190Y-383194D01*
X217186Y-383186D01*
X217183Y-383183D01*
X217153Y-383131D01*
X217127Y-383079D01*
X217087Y-382968D01*
X217057Y-382857D01*
X217038Y-382750D01*
X217031Y-382698D01*
X217024Y-382653D01*
X217020Y-382613D01*
Y-382579D01*
X217016Y-382550D01*
Y-382509D01*
X217020Y-382435D01*
X217027Y-382365D01*
X217035Y-382298D01*
X217050Y-382235D01*
X217068Y-382176D01*
X217087Y-382121D01*
X217105Y-382069D01*
X217127Y-382021D01*
X217146Y-381980D01*
X217164Y-381939D01*
X217183Y-381910D01*
X217201Y-381880D01*
X217216Y-381862D01*
X217224Y-381843D01*
X217231Y-381836D01*
X217235Y-381832D01*
X217279Y-381780D01*
X217323Y-381736D01*
X217375Y-381695D01*
X217427Y-381655D01*
X217531Y-381588D01*
X217634Y-381536D01*
X217682Y-381514D01*
X217727Y-381495D01*
X217768Y-381481D01*
X217801Y-381469D01*
X217830Y-381458D01*
X217853Y-381451D01*
X217867Y-381447D01*
X217871D01*
X217956Y-381788D01*
D02*
G37*
G36*
X223137Y-367343D02*
X222833D01*
Y-366089D01*
X222726Y-366177D01*
X222611Y-366263D01*
X222500Y-366336D01*
X222393Y-366407D01*
X222345Y-366436D01*
X222301Y-366462D01*
X222260Y-366488D01*
X222227Y-366507D01*
X222197Y-366522D01*
X222179Y-366533D01*
X222164Y-366540D01*
X222160Y-366544D01*
X222012Y-366618D01*
X221864Y-366684D01*
X221723Y-366740D01*
X221660Y-366762D01*
X221598Y-366784D01*
X221542Y-366806D01*
X221490Y-366821D01*
X221446Y-366836D01*
X221409Y-366847D01*
X221376Y-366858D01*
X221353Y-366866D01*
X221339Y-366869D01*
X221335D01*
X221183Y-366906D01*
X221109Y-366921D01*
X221042Y-366932D01*
X220980Y-366943D01*
X220917Y-366954D01*
X220865Y-366962D01*
X220813Y-366969D01*
X220769Y-366973D01*
X220728Y-366977D01*
X220691Y-366980D01*
X220661D01*
X220639Y-366984D01*
X220624D01*
X220613D01*
X220610D01*
Y-366662D01*
X220750Y-366651D01*
X220880Y-366633D01*
X220998Y-366614D01*
X221054Y-366603D01*
X221106Y-366592D01*
X221150Y-366584D01*
X221191Y-366573D01*
X221228Y-366566D01*
X221257Y-366559D01*
X221279Y-366551D01*
X221298Y-366547D01*
X221309Y-366544D01*
X221313D01*
X221483Y-366488D01*
X221642Y-366429D01*
X221720Y-366399D01*
X221794Y-366370D01*
X221860Y-366336D01*
X221927Y-366307D01*
X221986Y-366281D01*
X222038Y-366255D01*
X222082Y-366233D01*
X222123Y-366214D01*
X222156Y-366196D01*
X222179Y-366185D01*
X222193Y-366177D01*
X222197Y-366174D01*
X222275Y-366129D01*
X222352Y-366085D01*
X222423Y-366040D01*
X222489Y-365996D01*
X222549Y-365955D01*
X222608Y-365915D01*
X222659Y-365874D01*
X222704Y-365841D01*
X222748Y-365807D01*
X222785Y-365778D01*
X222815Y-365748D01*
X222841Y-365726D01*
X222863Y-365711D01*
X222878Y-365696D01*
X222885Y-365689D01*
X222889Y-365685D01*
X223137D01*
Y-367343D01*
D02*
G37*
G36*
X221512Y-368035D02*
X223170D01*
Y-368290D01*
X221512Y-369463D01*
X221224D01*
Y-368349D01*
X220610D01*
Y-368035D01*
X221224D01*
Y-367687D01*
X221512D01*
Y-368035D01*
D02*
G37*
G36*
X221505Y-369985D02*
X221446Y-370000D01*
X221390Y-370018D01*
X221339Y-370037D01*
X221290Y-370055D01*
X221246Y-370077D01*
X221209Y-370099D01*
X221172Y-370125D01*
X221139Y-370147D01*
X221109Y-370166D01*
X221087Y-370188D01*
X221065Y-370207D01*
X221046Y-370221D01*
X221035Y-370236D01*
X221024Y-370247D01*
X221020Y-370251D01*
X221017Y-370255D01*
X220987Y-370292D01*
X220965Y-370333D01*
X220924Y-370414D01*
X220895Y-370492D01*
X220876Y-370569D01*
X220861Y-370636D01*
X220858Y-370662D01*
Y-370688D01*
X220854Y-370710D01*
Y-370736D01*
X220858Y-370821D01*
X220872Y-370902D01*
X220891Y-370976D01*
X220913Y-371043D01*
X220935Y-371095D01*
X220946Y-371117D01*
X220954Y-371135D01*
X220961Y-371150D01*
X220969Y-371161D01*
X220972Y-371169D01*
Y-371172D01*
X221024Y-371243D01*
X221080Y-371302D01*
X221143Y-371354D01*
X221202Y-371394D01*
X221253Y-371428D01*
X221298Y-371450D01*
X221316Y-371457D01*
X221327Y-371465D01*
X221335Y-371468D01*
X221339D01*
X221435Y-371498D01*
X221531Y-371520D01*
X221627Y-371539D01*
X221716Y-371550D01*
X221757Y-371553D01*
X221794Y-371557D01*
X221827D01*
X221853Y-371561D01*
X221875D01*
X221894D01*
X221905D01*
X221908D01*
X222005Y-371557D01*
X222093Y-371550D01*
X222175Y-371535D01*
X222249Y-371520D01*
X222312Y-371509D01*
X222338Y-371502D01*
X222360Y-371494D01*
X222378Y-371491D01*
X222389Y-371487D01*
X222397Y-371483D01*
X222400D01*
X222486Y-371446D01*
X222563Y-371406D01*
X222626Y-371361D01*
X222682Y-371313D01*
X222726Y-371272D01*
X222756Y-371239D01*
X222774Y-371213D01*
X222782Y-371209D01*
Y-371206D01*
X222830Y-371128D01*
X222867Y-371043D01*
X222892Y-370961D01*
X222907Y-370884D01*
X222918Y-370813D01*
X222922Y-370784D01*
Y-370758D01*
X222926Y-370740D01*
Y-370710D01*
X222922Y-370617D01*
X222907Y-370532D01*
X222885Y-370462D01*
X222863Y-370399D01*
X222837Y-370351D01*
X222819Y-370314D01*
X222804Y-370292D01*
X222796Y-370284D01*
X222741Y-370225D01*
X222678Y-370170D01*
X222611Y-370125D01*
X222545Y-370088D01*
X222486Y-370059D01*
X222456Y-370048D01*
X222434Y-370040D01*
X222415Y-370033D01*
X222400Y-370025D01*
X222393Y-370022D01*
X222389D01*
X222467Y-369689D01*
X222534Y-369711D01*
X222593Y-369733D01*
X222648Y-369763D01*
X222704Y-369789D01*
X222752Y-369818D01*
X222796Y-369851D01*
X222841Y-369881D01*
X222878Y-369911D01*
X222907Y-369940D01*
X222937Y-369966D01*
X222963Y-369992D01*
X222981Y-370011D01*
X223000Y-370029D01*
X223011Y-370044D01*
X223015Y-370051D01*
X223018Y-370055D01*
X223052Y-370107D01*
X223085Y-370159D01*
X223111Y-370210D01*
X223133Y-370266D01*
X223166Y-370377D01*
X223188Y-370477D01*
X223200Y-370525D01*
X223203Y-370566D01*
X223207Y-370606D01*
X223211Y-370640D01*
X223214Y-370666D01*
Y-370703D01*
X223207Y-370825D01*
X223188Y-370943D01*
X223166Y-371047D01*
X223151Y-371095D01*
X223137Y-371139D01*
X223122Y-371180D01*
X223107Y-371217D01*
X223096Y-371246D01*
X223085Y-371276D01*
X223074Y-371294D01*
X223066Y-371309D01*
X223063Y-371320D01*
X223059Y-371324D01*
X222996Y-371424D01*
X222922Y-371509D01*
X222848Y-371583D01*
X222774Y-371646D01*
X222708Y-371694D01*
X222678Y-371713D01*
X222652Y-371727D01*
X222634Y-371742D01*
X222619Y-371750D01*
X222608Y-371753D01*
X222604Y-371757D01*
X222489Y-371809D01*
X222371Y-371846D01*
X222252Y-371872D01*
X222145Y-371890D01*
X222097Y-371898D01*
X222049Y-371901D01*
X222012Y-371905D01*
X221975D01*
X221949Y-371909D01*
X221927D01*
X221912D01*
X221908D01*
X221775Y-371901D01*
X221646Y-371886D01*
X221531Y-371868D01*
X221476Y-371853D01*
X221427Y-371842D01*
X221383Y-371831D01*
X221342Y-371816D01*
X221305Y-371805D01*
X221276Y-371798D01*
X221253Y-371787D01*
X221235Y-371783D01*
X221224Y-371776D01*
X221220D01*
X221109Y-371720D01*
X221009Y-371657D01*
X220924Y-371590D01*
X220891Y-371557D01*
X220858Y-371528D01*
X220828Y-371498D01*
X220802Y-371468D01*
X220780Y-371443D01*
X220765Y-371420D01*
X220750Y-371406D01*
X220739Y-371391D01*
X220735Y-371383D01*
X220732Y-371380D01*
X220702Y-371328D01*
X220676Y-371276D01*
X220636Y-371165D01*
X220606Y-371054D01*
X220587Y-370947D01*
X220580Y-370895D01*
X220573Y-370850D01*
X220569Y-370810D01*
Y-370777D01*
X220565Y-370747D01*
Y-370706D01*
X220569Y-370632D01*
X220576Y-370562D01*
X220584Y-370495D01*
X220599Y-370432D01*
X220617Y-370373D01*
X220636Y-370318D01*
X220654Y-370266D01*
X220676Y-370218D01*
X220695Y-370177D01*
X220713Y-370136D01*
X220732Y-370107D01*
X220750Y-370077D01*
X220765Y-370059D01*
X220772Y-370040D01*
X220780Y-370033D01*
X220784Y-370029D01*
X220828Y-369977D01*
X220872Y-369933D01*
X220924Y-369892D01*
X220976Y-369851D01*
X221080Y-369785D01*
X221183Y-369733D01*
X221231Y-369711D01*
X221276Y-369692D01*
X221316Y-369678D01*
X221350Y-369667D01*
X221379Y-369655D01*
X221402Y-369648D01*
X221416Y-369644D01*
X221420D01*
X221505Y-369985D01*
D02*
G37*
G36*
X236724Y-365691D02*
X236801Y-365706D01*
X236872Y-365728D01*
X236931Y-365750D01*
X236979Y-365772D01*
X237016Y-365794D01*
X237038Y-365809D01*
X237042Y-365813D01*
X237046D01*
X237105Y-365865D01*
X237157Y-365920D01*
X237197Y-365980D01*
X237234Y-366035D01*
X237260Y-366087D01*
X237279Y-366131D01*
X237286Y-366146D01*
X237290Y-366157D01*
X237293Y-366164D01*
Y-366168D01*
X237323Y-366102D01*
X237356Y-366046D01*
X237390Y-365998D01*
X237423Y-365957D01*
X237453Y-365928D01*
X237475Y-365905D01*
X237490Y-365891D01*
X237497Y-365887D01*
X237549Y-365854D01*
X237600Y-365831D01*
X237652Y-365813D01*
X237704Y-365802D01*
X237745Y-365794D01*
X237778Y-365791D01*
X237800D01*
X237804D01*
X237808D01*
X237860Y-365794D01*
X237908Y-365798D01*
X238000Y-365824D01*
X238082Y-365857D01*
X238152Y-365894D01*
X238207Y-365931D01*
X238229Y-365950D01*
X238252Y-365965D01*
X238266Y-365980D01*
X238278Y-365991D01*
X238281Y-365994D01*
X238285Y-365998D01*
X238318Y-366039D01*
X238352Y-366079D01*
X238377Y-366124D01*
X238400Y-366168D01*
X238433Y-366257D01*
X238455Y-366346D01*
X238466Y-366383D01*
X238470Y-366420D01*
X238474Y-366453D01*
X238477Y-366483D01*
X238481Y-366505D01*
Y-366538D01*
X238477Y-366597D01*
X238474Y-366657D01*
X238452Y-366760D01*
X238437Y-366808D01*
X238422Y-366853D01*
X238403Y-366893D01*
X238385Y-366930D01*
X238366Y-366960D01*
X238348Y-366990D01*
X238333Y-367016D01*
X238318Y-367034D01*
X238307Y-367049D01*
X238296Y-367060D01*
X238292Y-367067D01*
X238289Y-367071D01*
X238252Y-367104D01*
X238215Y-367138D01*
X238174Y-367163D01*
X238133Y-367186D01*
X238056Y-367223D01*
X237982Y-367245D01*
X237919Y-367260D01*
X237889Y-367263D01*
X237867Y-367267D01*
X237845Y-367271D01*
X237830D01*
X237823D01*
X237819D01*
X237752Y-367267D01*
X237689Y-367256D01*
X237634Y-367241D01*
X237586Y-367223D01*
X237549Y-367208D01*
X237519Y-367193D01*
X237504Y-367182D01*
X237497Y-367178D01*
X237453Y-367138D01*
X237412Y-367093D01*
X237375Y-367045D01*
X237345Y-366997D01*
X237323Y-366953D01*
X237308Y-366919D01*
X237301Y-366904D01*
X237297Y-366893D01*
X237293Y-366890D01*
Y-366886D01*
X237267Y-366971D01*
X237234Y-367041D01*
X237193Y-367104D01*
X237157Y-367156D01*
X237120Y-367197D01*
X237090Y-367226D01*
X237071Y-367241D01*
X237068Y-367249D01*
X237064D01*
X236997Y-367289D01*
X236927Y-367323D01*
X236860Y-367345D01*
X236794Y-367360D01*
X236735Y-367367D01*
X236709Y-367371D01*
X236687D01*
X236672Y-367374D01*
X236657D01*
X236650D01*
X236646D01*
X236587Y-367371D01*
X236527Y-367363D01*
X236472Y-367352D01*
X236417Y-367337D01*
X236324Y-367300D01*
X236280Y-367282D01*
X236243Y-367260D01*
X236206Y-367237D01*
X236176Y-367219D01*
X236150Y-367197D01*
X236128Y-367182D01*
X236109Y-367167D01*
X236098Y-367156D01*
X236091Y-367149D01*
X236087Y-367145D01*
X236047Y-367101D01*
X236013Y-367053D01*
X235984Y-367001D01*
X235958Y-366949D01*
X235939Y-366901D01*
X235921Y-366849D01*
X235895Y-366749D01*
X235884Y-366705D01*
X235876Y-366664D01*
X235873Y-366627D01*
X235869Y-366594D01*
X235865Y-366568D01*
Y-366531D01*
X235869Y-366460D01*
X235876Y-366398D01*
X235887Y-366335D01*
X235898Y-366276D01*
X235917Y-366224D01*
X235935Y-366172D01*
X235954Y-366124D01*
X235976Y-366083D01*
X235998Y-366046D01*
X236017Y-366013D01*
X236035Y-365987D01*
X236054Y-365961D01*
X236065Y-365943D01*
X236076Y-365931D01*
X236084Y-365924D01*
X236087Y-365920D01*
X236132Y-365880D01*
X236176Y-365843D01*
X236220Y-365813D01*
X236268Y-365787D01*
X236313Y-365761D01*
X236361Y-365743D01*
X236446Y-365717D01*
X236487Y-365706D01*
X236524Y-365698D01*
X236557Y-365695D01*
X236583Y-365691D01*
X236605Y-365687D01*
X236624D01*
X236635D01*
X236638D01*
X236724Y-365691D01*
D02*
G37*
G36*
X236812Y-368040D02*
X238470D01*
Y-368296D01*
X236812Y-369469D01*
X236524D01*
Y-368355D01*
X235910D01*
Y-368040D01*
X236524D01*
Y-367693D01*
X236812D01*
Y-368040D01*
D02*
G37*
G36*
X236805Y-369990D02*
X236746Y-370005D01*
X236690Y-370024D01*
X236638Y-370042D01*
X236590Y-370061D01*
X236546Y-370083D01*
X236509Y-370105D01*
X236472Y-370131D01*
X236439Y-370153D01*
X236409Y-370172D01*
X236387Y-370194D01*
X236365Y-370212D01*
X236346Y-370227D01*
X236335Y-370242D01*
X236324Y-370253D01*
X236320Y-370257D01*
X236317Y-370260D01*
X236287Y-370297D01*
X236265Y-370338D01*
X236224Y-370420D01*
X236194Y-370497D01*
X236176Y-370575D01*
X236161Y-370641D01*
X236157Y-370667D01*
Y-370693D01*
X236154Y-370715D01*
Y-370741D01*
X236157Y-370827D01*
X236172Y-370908D01*
X236191Y-370982D01*
X236213Y-371048D01*
X236235Y-371100D01*
X236246Y-371123D01*
X236254Y-371141D01*
X236261Y-371156D01*
X236268Y-371167D01*
X236272Y-371174D01*
Y-371178D01*
X236324Y-371248D01*
X236380Y-371307D01*
X236442Y-371359D01*
X236502Y-371400D01*
X236553Y-371433D01*
X236598Y-371456D01*
X236616Y-371463D01*
X236627Y-371470D01*
X236635Y-371474D01*
X236638D01*
X236735Y-371504D01*
X236831Y-371526D01*
X236927Y-371544D01*
X237016Y-371555D01*
X237057Y-371559D01*
X237094Y-371563D01*
X237127D01*
X237153Y-371567D01*
X237175D01*
X237193D01*
X237205D01*
X237208D01*
X237304Y-371563D01*
X237393Y-371555D01*
X237475Y-371541D01*
X237549Y-371526D01*
X237612Y-371515D01*
X237637Y-371507D01*
X237660Y-371500D01*
X237678Y-371496D01*
X237689Y-371493D01*
X237697Y-371489D01*
X237700D01*
X237786Y-371452D01*
X237863Y-371411D01*
X237926Y-371367D01*
X237982Y-371319D01*
X238026Y-371278D01*
X238056Y-371245D01*
X238074Y-371219D01*
X238082Y-371215D01*
Y-371211D01*
X238130Y-371134D01*
X238167Y-371048D01*
X238193Y-370967D01*
X238207Y-370889D01*
X238218Y-370819D01*
X238222Y-370790D01*
Y-370764D01*
X238226Y-370745D01*
Y-370715D01*
X238222Y-370623D01*
X238207Y-370538D01*
X238185Y-370468D01*
X238163Y-370405D01*
X238137Y-370357D01*
X238119Y-370320D01*
X238104Y-370297D01*
X238096Y-370290D01*
X238041Y-370231D01*
X237978Y-370175D01*
X237911Y-370131D01*
X237845Y-370094D01*
X237786Y-370064D01*
X237756Y-370053D01*
X237734Y-370046D01*
X237715Y-370038D01*
X237700Y-370031D01*
X237693Y-370027D01*
X237689D01*
X237767Y-369694D01*
X237834Y-369717D01*
X237893Y-369739D01*
X237948Y-369768D01*
X238004Y-369794D01*
X238052Y-369824D01*
X238096Y-369857D01*
X238141Y-369887D01*
X238178Y-369916D01*
X238207Y-369946D01*
X238237Y-369972D01*
X238263Y-369998D01*
X238281Y-370016D01*
X238300Y-370035D01*
X238311Y-370050D01*
X238315Y-370057D01*
X238318Y-370061D01*
X238352Y-370112D01*
X238385Y-370164D01*
X238411Y-370216D01*
X238433Y-370271D01*
X238466Y-370382D01*
X238489Y-370482D01*
X238500Y-370531D01*
X238503Y-370571D01*
X238507Y-370612D01*
X238511Y-370645D01*
X238514Y-370671D01*
Y-370708D01*
X238507Y-370830D01*
X238489Y-370949D01*
X238466Y-371052D01*
X238452Y-371100D01*
X238437Y-371145D01*
X238422Y-371185D01*
X238407Y-371222D01*
X238396Y-371252D01*
X238385Y-371282D01*
X238374Y-371300D01*
X238366Y-371315D01*
X238363Y-371326D01*
X238359Y-371330D01*
X238296Y-371430D01*
X238222Y-371515D01*
X238148Y-371589D01*
X238074Y-371652D01*
X238007Y-371700D01*
X237978Y-371718D01*
X237952Y-371733D01*
X237933Y-371748D01*
X237919Y-371755D01*
X237908Y-371759D01*
X237904Y-371763D01*
X237789Y-371814D01*
X237671Y-371851D01*
X237552Y-371877D01*
X237445Y-371896D01*
X237397Y-371903D01*
X237349Y-371907D01*
X237312Y-371911D01*
X237275D01*
X237249Y-371914D01*
X237227D01*
X237212D01*
X237208D01*
X237075Y-371907D01*
X236946Y-371892D01*
X236831Y-371874D01*
X236775Y-371859D01*
X236727Y-371848D01*
X236683Y-371837D01*
X236642Y-371822D01*
X236605Y-371811D01*
X236576Y-371803D01*
X236553Y-371792D01*
X236535Y-371789D01*
X236524Y-371781D01*
X236520D01*
X236409Y-371726D01*
X236309Y-371663D01*
X236224Y-371596D01*
X236191Y-371563D01*
X236157Y-371533D01*
X236128Y-371504D01*
X236102Y-371474D01*
X236080Y-371448D01*
X236065Y-371426D01*
X236050Y-371411D01*
X236039Y-371396D01*
X236035Y-371389D01*
X236032Y-371385D01*
X236002Y-371333D01*
X235976Y-371282D01*
X235935Y-371171D01*
X235906Y-371060D01*
X235887Y-370952D01*
X235880Y-370901D01*
X235873Y-370856D01*
X235869Y-370815D01*
Y-370782D01*
X235865Y-370753D01*
Y-370712D01*
X235869Y-370638D01*
X235876Y-370567D01*
X235884Y-370501D01*
X235898Y-370438D01*
X235917Y-370379D01*
X235935Y-370323D01*
X235954Y-370271D01*
X235976Y-370223D01*
X235995Y-370183D01*
X236013Y-370142D01*
X236032Y-370112D01*
X236050Y-370083D01*
X236065Y-370064D01*
X236072Y-370046D01*
X236080Y-370038D01*
X236084Y-370035D01*
X236128Y-369983D01*
X236172Y-369938D01*
X236224Y-369898D01*
X236276Y-369857D01*
X236380Y-369791D01*
X236483Y-369739D01*
X236531Y-369717D01*
X236576Y-369698D01*
X236616Y-369683D01*
X236650Y-369672D01*
X236679Y-369661D01*
X236701Y-369654D01*
X236716Y-369650D01*
X236720D01*
X236805Y-369990D01*
D02*
G37*
G36*
X241408Y-365691D02*
X241482Y-365698D01*
X241552Y-365706D01*
X241615Y-365713D01*
X241674Y-365721D01*
X241730Y-365732D01*
X241778Y-365743D01*
X241819Y-365754D01*
X241856Y-365761D01*
X241889Y-365772D01*
X241915Y-365780D01*
X241933Y-365787D01*
X241948Y-365794D01*
X241956Y-365798D01*
X241959D01*
X242048Y-365843D01*
X242126Y-365891D01*
X242193Y-365946D01*
X242248Y-365994D01*
X242289Y-366042D01*
X242318Y-366079D01*
X242329Y-366094D01*
X242337Y-366105D01*
X242344Y-366109D01*
Y-366113D01*
X242389Y-366190D01*
X242422Y-366268D01*
X242448Y-366346D01*
X242463Y-366416D01*
X242474Y-366479D01*
X242477Y-366505D01*
Y-366523D01*
X242481Y-366542D01*
Y-366568D01*
X242477Y-366631D01*
X242470Y-366690D01*
X242459Y-366749D01*
X242444Y-366801D01*
X242403Y-366901D01*
X242385Y-366945D01*
X242363Y-366982D01*
X242337Y-367019D01*
X242318Y-367049D01*
X242296Y-367078D01*
X242278Y-367101D01*
X242263Y-367119D01*
X242252Y-367130D01*
X242244Y-367138D01*
X242241Y-367141D01*
X242196Y-367182D01*
X242144Y-367215D01*
X242096Y-367249D01*
X242044Y-367274D01*
X241989Y-367297D01*
X241937Y-367315D01*
X241841Y-367341D01*
X241793Y-367352D01*
X241752Y-367360D01*
X241711Y-367363D01*
X241678Y-367367D01*
X241652Y-367371D01*
X241634D01*
X241619D01*
X241615D01*
X241545Y-367367D01*
X241482Y-367360D01*
X241419Y-367352D01*
X241360Y-367337D01*
X241308Y-367319D01*
X241256Y-367300D01*
X241212Y-367282D01*
X241171Y-367260D01*
X241134Y-367241D01*
X241101Y-367223D01*
X241075Y-367204D01*
X241049Y-367186D01*
X241031Y-367171D01*
X241020Y-367163D01*
X241012Y-367156D01*
X241008Y-367152D01*
X240968Y-367112D01*
X240934Y-367067D01*
X240901Y-367023D01*
X240875Y-366975D01*
X240853Y-366930D01*
X240835Y-366886D01*
X240809Y-366801D01*
X240798Y-366764D01*
X240790Y-366727D01*
X240787Y-366697D01*
X240783Y-366668D01*
X240779Y-366646D01*
Y-366616D01*
X240783Y-366546D01*
X240794Y-366479D01*
X240809Y-366420D01*
X240827Y-366364D01*
X240842Y-366324D01*
X240857Y-366290D01*
X240868Y-366268D01*
X240872Y-366261D01*
X240909Y-366201D01*
X240949Y-366150D01*
X240990Y-366105D01*
X241027Y-366068D01*
X241064Y-366042D01*
X241090Y-366020D01*
X241108Y-366005D01*
X241116Y-366002D01*
X241086D01*
X241068D01*
X241057D01*
X241053D01*
X240979Y-366005D01*
X240909Y-366009D01*
X240846Y-366017D01*
X240787Y-366024D01*
X240738Y-366035D01*
X240701Y-366042D01*
X240687Y-366046D01*
X240675D01*
X240672Y-366050D01*
X240668D01*
X240601Y-366068D01*
X240542Y-366087D01*
X240491Y-366105D01*
X240446Y-366124D01*
X240413Y-366139D01*
X240387Y-366153D01*
X240368Y-366161D01*
X240365Y-366164D01*
X240324Y-366194D01*
X240291Y-366224D01*
X240261Y-366253D01*
X240235Y-366283D01*
X240213Y-366305D01*
X240198Y-366327D01*
X240191Y-366342D01*
X240187Y-366346D01*
X240165Y-366387D01*
X240150Y-366431D01*
X240139Y-366472D01*
X240132Y-366512D01*
X240128Y-366546D01*
X240124Y-366571D01*
Y-366597D01*
X240128Y-366657D01*
X240139Y-366712D01*
X240154Y-366760D01*
X240172Y-366801D01*
X240187Y-366830D01*
X240202Y-366856D01*
X240213Y-366871D01*
X240217Y-366875D01*
X240257Y-366912D01*
X240305Y-366941D01*
X240357Y-366967D01*
X240409Y-366986D01*
X240454Y-367001D01*
X240494Y-367012D01*
X240509Y-367016D01*
X240516D01*
X240524Y-367019D01*
X240528D01*
X240502Y-367323D01*
X240394Y-367300D01*
X240302Y-367271D01*
X240220Y-367234D01*
X240154Y-367197D01*
X240102Y-367160D01*
X240080Y-367141D01*
X240061Y-367126D01*
X240050Y-367115D01*
X240039Y-367104D01*
X240035Y-367101D01*
X240032Y-367097D01*
X240002Y-367060D01*
X239976Y-367019D01*
X239935Y-366938D01*
X239906Y-366856D01*
X239887Y-366779D01*
X239873Y-366708D01*
X239869Y-366679D01*
Y-366653D01*
X239865Y-366634D01*
Y-366605D01*
X239873Y-366501D01*
X239887Y-366409D01*
X239913Y-366324D01*
X239943Y-366253D01*
X239954Y-366224D01*
X239969Y-366194D01*
X239984Y-366172D01*
X239995Y-366150D01*
X240002Y-366135D01*
X240009Y-366124D01*
X240017Y-366116D01*
Y-366113D01*
X240080Y-366039D01*
X240150Y-365972D01*
X240224Y-365920D01*
X240294Y-365876D01*
X240357Y-365839D01*
X240387Y-365824D01*
X240409Y-365813D01*
X240431Y-365806D01*
X240446Y-365798D01*
X240454Y-365794D01*
X240457D01*
X240513Y-365776D01*
X240576Y-365757D01*
X240701Y-365732D01*
X240835Y-365713D01*
X240960Y-365702D01*
X241016Y-365695D01*
X241071Y-365691D01*
X241120D01*
X241160Y-365687D01*
X241194D01*
X241219D01*
X241238D01*
X241242D01*
X241327D01*
X241408Y-365691D01*
D02*
G37*
G36*
X240812Y-368040D02*
X242470D01*
Y-368296D01*
X240812Y-369469D01*
X240524D01*
Y-368355D01*
X239910D01*
Y-368040D01*
X240524D01*
Y-367693D01*
X240812D01*
Y-368040D01*
D02*
G37*
G36*
X240805Y-369990D02*
X240746Y-370005D01*
X240690Y-370024D01*
X240638Y-370042D01*
X240590Y-370061D01*
X240546Y-370083D01*
X240509Y-370105D01*
X240472Y-370131D01*
X240439Y-370153D01*
X240409Y-370172D01*
X240387Y-370194D01*
X240365Y-370212D01*
X240346Y-370227D01*
X240335Y-370242D01*
X240324Y-370253D01*
X240320Y-370257D01*
X240317Y-370260D01*
X240287Y-370297D01*
X240265Y-370338D01*
X240224Y-370420D01*
X240195Y-370497D01*
X240176Y-370575D01*
X240161Y-370641D01*
X240158Y-370667D01*
Y-370693D01*
X240154Y-370715D01*
Y-370741D01*
X240158Y-370827D01*
X240172Y-370908D01*
X240191Y-370982D01*
X240213Y-371048D01*
X240235Y-371100D01*
X240246Y-371123D01*
X240254Y-371141D01*
X240261Y-371156D01*
X240268Y-371167D01*
X240272Y-371174D01*
Y-371178D01*
X240324Y-371248D01*
X240380Y-371307D01*
X240442Y-371359D01*
X240502Y-371400D01*
X240553Y-371433D01*
X240598Y-371456D01*
X240616Y-371463D01*
X240627Y-371470D01*
X240635Y-371474D01*
X240638D01*
X240735Y-371504D01*
X240831Y-371526D01*
X240927Y-371544D01*
X241016Y-371555D01*
X241057Y-371559D01*
X241094Y-371563D01*
X241127D01*
X241153Y-371567D01*
X241175D01*
X241194D01*
X241205D01*
X241208D01*
X241304Y-371563D01*
X241393Y-371555D01*
X241475Y-371541D01*
X241549Y-371526D01*
X241612Y-371515D01*
X241637Y-371507D01*
X241660Y-371500D01*
X241678Y-371496D01*
X241689Y-371493D01*
X241697Y-371489D01*
X241700D01*
X241786Y-371452D01*
X241863Y-371411D01*
X241926Y-371367D01*
X241982Y-371319D01*
X242026Y-371278D01*
X242056Y-371245D01*
X242074Y-371219D01*
X242081Y-371215D01*
Y-371211D01*
X242130Y-371134D01*
X242167Y-371048D01*
X242193Y-370967D01*
X242207Y-370889D01*
X242218Y-370819D01*
X242222Y-370790D01*
Y-370764D01*
X242226Y-370745D01*
Y-370715D01*
X242222Y-370623D01*
X242207Y-370538D01*
X242185Y-370468D01*
X242163Y-370405D01*
X242137Y-370357D01*
X242119Y-370320D01*
X242104Y-370297D01*
X242096Y-370290D01*
X242041Y-370231D01*
X241978Y-370175D01*
X241911Y-370131D01*
X241845Y-370094D01*
X241786Y-370064D01*
X241756Y-370053D01*
X241734Y-370046D01*
X241715Y-370038D01*
X241700Y-370031D01*
X241693Y-370027D01*
X241689D01*
X241767Y-369694D01*
X241834Y-369717D01*
X241893Y-369739D01*
X241948Y-369768D01*
X242004Y-369794D01*
X242052Y-369824D01*
X242096Y-369857D01*
X242141Y-369887D01*
X242178Y-369916D01*
X242207Y-369946D01*
X242237Y-369972D01*
X242263Y-369998D01*
X242281Y-370016D01*
X242300Y-370035D01*
X242311Y-370050D01*
X242315Y-370057D01*
X242318Y-370061D01*
X242352Y-370112D01*
X242385Y-370164D01*
X242411Y-370216D01*
X242433Y-370271D01*
X242466Y-370382D01*
X242489Y-370482D01*
X242500Y-370531D01*
X242503Y-370571D01*
X242507Y-370612D01*
X242511Y-370645D01*
X242514Y-370671D01*
Y-370708D01*
X242507Y-370830D01*
X242489Y-370949D01*
X242466Y-371052D01*
X242452Y-371100D01*
X242437Y-371145D01*
X242422Y-371185D01*
X242407Y-371222D01*
X242396Y-371252D01*
X242385Y-371282D01*
X242374Y-371300D01*
X242366Y-371315D01*
X242363Y-371326D01*
X242359Y-371330D01*
X242296Y-371430D01*
X242222Y-371515D01*
X242148Y-371589D01*
X242074Y-371652D01*
X242007Y-371700D01*
X241978Y-371718D01*
X241952Y-371733D01*
X241933Y-371748D01*
X241919Y-371755D01*
X241908Y-371759D01*
X241904Y-371763D01*
X241789Y-371814D01*
X241671Y-371851D01*
X241552Y-371877D01*
X241445Y-371896D01*
X241397Y-371903D01*
X241349Y-371907D01*
X241312Y-371911D01*
X241275D01*
X241249Y-371914D01*
X241227D01*
X241212D01*
X241208D01*
X241075Y-371907D01*
X240946Y-371892D01*
X240831Y-371874D01*
X240775Y-371859D01*
X240727Y-371848D01*
X240683Y-371837D01*
X240642Y-371822D01*
X240605Y-371811D01*
X240576Y-371803D01*
X240553Y-371792D01*
X240535Y-371789D01*
X240524Y-371781D01*
X240520D01*
X240409Y-371726D01*
X240309Y-371663D01*
X240224Y-371596D01*
X240191Y-371563D01*
X240158Y-371533D01*
X240128Y-371504D01*
X240102Y-371474D01*
X240080Y-371448D01*
X240065Y-371426D01*
X240050Y-371411D01*
X240039Y-371396D01*
X240035Y-371389D01*
X240032Y-371385D01*
X240002Y-371333D01*
X239976Y-371282D01*
X239935Y-371171D01*
X239906Y-371060D01*
X239887Y-370952D01*
X239880Y-370901D01*
X239873Y-370856D01*
X239869Y-370815D01*
Y-370782D01*
X239865Y-370753D01*
Y-370712D01*
X239869Y-370638D01*
X239876Y-370567D01*
X239884Y-370501D01*
X239898Y-370438D01*
X239917Y-370379D01*
X239935Y-370323D01*
X239954Y-370271D01*
X239976Y-370223D01*
X239995Y-370183D01*
X240013Y-370142D01*
X240032Y-370112D01*
X240050Y-370083D01*
X240065Y-370064D01*
X240072Y-370046D01*
X240080Y-370038D01*
X240084Y-370035D01*
X240128Y-369983D01*
X240172Y-369938D01*
X240224Y-369898D01*
X240276Y-369857D01*
X240380Y-369791D01*
X240483Y-369739D01*
X240531Y-369717D01*
X240576Y-369698D01*
X240616Y-369683D01*
X240650Y-369672D01*
X240679Y-369661D01*
X240701Y-369654D01*
X240716Y-369650D01*
X240720D01*
X240805Y-369990D01*
D02*
G37*
G36*
X252808Y-365685D02*
X252868D01*
X252927Y-365689D01*
X252978Y-365696D01*
X253030Y-365700D01*
X253075Y-365704D01*
X253115Y-365711D01*
X253152Y-365715D01*
X253186Y-365722D01*
X253211Y-365726D01*
X253234Y-365730D01*
X253252Y-365733D01*
X253263Y-365737D01*
X253271Y-365741D01*
X253274D01*
X253356Y-365763D01*
X253430Y-365789D01*
X253493Y-365819D01*
X253548Y-365841D01*
X253596Y-365867D01*
X253630Y-365881D01*
X253648Y-365896D01*
X253656Y-365900D01*
X253711Y-365941D01*
X253759Y-365981D01*
X253800Y-366026D01*
X253837Y-366066D01*
X253863Y-366103D01*
X253881Y-366133D01*
X253892Y-366151D01*
X253896Y-366155D01*
Y-366159D01*
X253926Y-366218D01*
X253944Y-366281D01*
X253959Y-366340D01*
X253970Y-366396D01*
X253977Y-366444D01*
X253981Y-366484D01*
Y-366518D01*
X253974Y-366618D01*
X253959Y-366710D01*
X253933Y-366788D01*
X253907Y-366855D01*
X253878Y-366910D01*
X253866Y-366932D01*
X253852Y-366951D01*
X253844Y-366966D01*
X253837Y-366977D01*
X253829Y-366980D01*
Y-366984D01*
X253770Y-367051D01*
X253700Y-367106D01*
X253630Y-367154D01*
X253563Y-367191D01*
X253500Y-367221D01*
X253474Y-367236D01*
X253448Y-367243D01*
X253430Y-367250D01*
X253415Y-367258D01*
X253408Y-367262D01*
X253404D01*
X253348Y-367276D01*
X253293Y-367291D01*
X253171Y-367313D01*
X253049Y-367332D01*
X252934Y-367343D01*
X252878Y-367347D01*
X252831Y-367350D01*
X252786D01*
X252745Y-367354D01*
X252716D01*
X252690D01*
X252675D01*
X252671D01*
X252542Y-367350D01*
X252420Y-367343D01*
X252309Y-367332D01*
X252205Y-367313D01*
X252109Y-367295D01*
X252024Y-367273D01*
X251946Y-367250D01*
X251880Y-367228D01*
X251820Y-367206D01*
X251769Y-367180D01*
X251724Y-367162D01*
X251691Y-367143D01*
X251661Y-367125D01*
X251643Y-367113D01*
X251632Y-367106D01*
X251628Y-367102D01*
X251584Y-367062D01*
X251543Y-367017D01*
X251506Y-366969D01*
X251476Y-366921D01*
X251450Y-366873D01*
X251428Y-366825D01*
X251413Y-366777D01*
X251398Y-366732D01*
X251387Y-366688D01*
X251380Y-366647D01*
X251373Y-366610D01*
X251369Y-366581D01*
X251365Y-366555D01*
Y-366518D01*
X251373Y-366418D01*
X251387Y-366325D01*
X251413Y-366248D01*
X251439Y-366181D01*
X251465Y-366126D01*
X251480Y-366107D01*
X251491Y-366089D01*
X251499Y-366074D01*
X251506Y-366063D01*
X251513Y-366059D01*
Y-366055D01*
X251576Y-365989D01*
X251643Y-365933D01*
X251717Y-365885D01*
X251783Y-365848D01*
X251846Y-365819D01*
X251872Y-365804D01*
X251898Y-365796D01*
X251917Y-365789D01*
X251931Y-365781D01*
X251939Y-365778D01*
X251942D01*
X251998Y-365759D01*
X252053Y-365744D01*
X252172Y-365722D01*
X252294Y-365704D01*
X252412Y-365693D01*
X252464Y-365689D01*
X252512Y-365685D01*
X252557D01*
X252597Y-365682D01*
X252627D01*
X252653D01*
X252668D01*
X252671D01*
X252742D01*
X252808Y-365685D01*
D02*
G37*
G36*
X252342Y-367650D02*
X252405Y-367657D01*
X252468Y-367669D01*
X252523Y-367683D01*
X252575Y-367702D01*
X252627Y-367720D01*
X252671Y-367742D01*
X252712Y-367761D01*
X252749Y-367783D01*
X252782Y-367805D01*
X252808Y-367824D01*
X252834Y-367842D01*
X252853Y-367857D01*
X252864Y-367868D01*
X252871Y-367876D01*
X252875Y-367879D01*
X252916Y-367924D01*
X252953Y-367968D01*
X252982Y-368016D01*
X253008Y-368064D01*
X253034Y-368112D01*
X253052Y-368161D01*
X253078Y-368249D01*
X253089Y-368290D01*
X253097Y-368327D01*
X253101Y-368360D01*
X253104Y-368390D01*
X253108Y-368412D01*
Y-368494D01*
X253101Y-368538D01*
X253082Y-368627D01*
X253056Y-368708D01*
X253027Y-368782D01*
X252997Y-368841D01*
X252982Y-368867D01*
X252971Y-368889D01*
X252960Y-368908D01*
X252953Y-368919D01*
X252949Y-368927D01*
X252945Y-368930D01*
X253637Y-368793D01*
Y-367768D01*
X253937D01*
Y-369041D01*
X252620Y-369289D01*
X252579Y-368993D01*
X252620Y-368967D01*
X252653Y-368934D01*
X252686Y-368904D01*
X252712Y-368875D01*
X252730Y-368845D01*
X252749Y-368823D01*
X252756Y-368808D01*
X252760Y-368804D01*
X252782Y-368756D01*
X252801Y-368708D01*
X252812Y-368664D01*
X252823Y-368619D01*
X252827Y-368582D01*
X252831Y-368553D01*
Y-368482D01*
X252823Y-368438D01*
X252805Y-368360D01*
X252779Y-368294D01*
X252753Y-368235D01*
X252723Y-368190D01*
X252697Y-368157D01*
X252679Y-368138D01*
X252675Y-368131D01*
X252671D01*
X252608Y-368079D01*
X252542Y-368042D01*
X252471Y-368016D01*
X252401Y-367998D01*
X252342Y-367987D01*
X252316Y-367983D01*
X252294D01*
X252275Y-367979D01*
X252261D01*
X252253D01*
X252250D01*
X252198D01*
X252150Y-367987D01*
X252057Y-368005D01*
X251979Y-368031D01*
X251917Y-368057D01*
X251865Y-368087D01*
X251824Y-368112D01*
X251813Y-368124D01*
X251802Y-368131D01*
X251798Y-368135D01*
X251795Y-368138D01*
X251765Y-368168D01*
X251739Y-368198D01*
X251694Y-368264D01*
X251665Y-368327D01*
X251646Y-368390D01*
X251632Y-368442D01*
X251628Y-368486D01*
X251624Y-368501D01*
Y-368523D01*
X251628Y-368594D01*
X251643Y-368656D01*
X251661Y-368712D01*
X251683Y-368756D01*
X251706Y-368797D01*
X251724Y-368827D01*
X251739Y-368841D01*
X251743Y-368849D01*
X251795Y-368893D01*
X251850Y-368930D01*
X251913Y-368960D01*
X251968Y-368982D01*
X252024Y-368997D01*
X252065Y-369008D01*
X252083Y-369012D01*
X252094Y-369015D01*
X252101D01*
X252105D01*
X252079Y-369345D01*
X252020Y-369337D01*
X251965Y-369326D01*
X251861Y-369293D01*
X251772Y-369252D01*
X251732Y-369230D01*
X251698Y-369208D01*
X251665Y-369189D01*
X251635Y-369167D01*
X251613Y-369148D01*
X251595Y-369130D01*
X251580Y-369115D01*
X251565Y-369108D01*
X251561Y-369100D01*
X251558Y-369097D01*
X251524Y-369052D01*
X251495Y-369008D01*
X251469Y-368960D01*
X251447Y-368912D01*
X251413Y-368819D01*
X251391Y-368727D01*
X251380Y-368686D01*
X251376Y-368645D01*
X251373Y-368612D01*
X251369Y-368582D01*
X251365Y-368556D01*
Y-368523D01*
X251369Y-368445D01*
X251380Y-368372D01*
X251395Y-368301D01*
X251413Y-368238D01*
X251439Y-368179D01*
X251465Y-368124D01*
X251491Y-368072D01*
X251521Y-368027D01*
X251550Y-367987D01*
X251576Y-367950D01*
X251606Y-367920D01*
X251628Y-367894D01*
X251646Y-367876D01*
X251661Y-367861D01*
X251672Y-367853D01*
X251676Y-367850D01*
X251724Y-367813D01*
X251776Y-367783D01*
X251824Y-367754D01*
X251876Y-367731D01*
X251976Y-367694D01*
X252072Y-367672D01*
X252113Y-367665D01*
X252153Y-367657D01*
X252187Y-367654D01*
X252216Y-367650D01*
X252242Y-367646D01*
X252261D01*
X252272D01*
X252275D01*
X252342Y-367650D01*
D02*
G37*
G36*
X252305Y-369974D02*
X252246Y-369988D01*
X252190Y-370007D01*
X252138Y-370025D01*
X252091Y-370044D01*
X252046Y-370066D01*
X252009Y-370088D01*
X251972Y-370114D01*
X251939Y-370136D01*
X251909Y-370155D01*
X251887Y-370177D01*
X251865Y-370196D01*
X251846Y-370210D01*
X251835Y-370225D01*
X251824Y-370236D01*
X251820Y-370240D01*
X251817Y-370244D01*
X251787Y-370281D01*
X251765Y-370321D01*
X251724Y-370403D01*
X251694Y-370480D01*
X251676Y-370558D01*
X251661Y-370625D01*
X251658Y-370651D01*
Y-370677D01*
X251654Y-370699D01*
Y-370725D01*
X251658Y-370810D01*
X251672Y-370891D01*
X251691Y-370965D01*
X251713Y-371032D01*
X251735Y-371084D01*
X251746Y-371106D01*
X251754Y-371124D01*
X251761Y-371139D01*
X251769Y-371150D01*
X251772Y-371158D01*
Y-371161D01*
X251824Y-371232D01*
X251880Y-371291D01*
X251942Y-371343D01*
X252002Y-371383D01*
X252053Y-371417D01*
X252098Y-371439D01*
X252116Y-371446D01*
X252127Y-371454D01*
X252135Y-371457D01*
X252138D01*
X252235Y-371487D01*
X252331Y-371509D01*
X252427Y-371528D01*
X252516Y-371539D01*
X252557Y-371542D01*
X252594Y-371546D01*
X252627D01*
X252653Y-371550D01*
X252675D01*
X252694D01*
X252705D01*
X252708D01*
X252805Y-371546D01*
X252893Y-371539D01*
X252975Y-371524D01*
X253049Y-371509D01*
X253112Y-371498D01*
X253138Y-371491D01*
X253160Y-371483D01*
X253178Y-371480D01*
X253189Y-371476D01*
X253197Y-371472D01*
X253201D01*
X253286Y-371435D01*
X253363Y-371394D01*
X253426Y-371350D01*
X253482Y-371302D01*
X253526Y-371261D01*
X253556Y-371228D01*
X253574Y-371202D01*
X253582Y-371198D01*
Y-371195D01*
X253630Y-371117D01*
X253667Y-371032D01*
X253693Y-370950D01*
X253707Y-370873D01*
X253718Y-370802D01*
X253722Y-370773D01*
Y-370747D01*
X253726Y-370728D01*
Y-370699D01*
X253722Y-370606D01*
X253707Y-370521D01*
X253685Y-370451D01*
X253663Y-370388D01*
X253637Y-370340D01*
X253619Y-370303D01*
X253604Y-370281D01*
X253596Y-370273D01*
X253541Y-370214D01*
X253478Y-370159D01*
X253411Y-370114D01*
X253345Y-370077D01*
X253286Y-370048D01*
X253256Y-370037D01*
X253234Y-370029D01*
X253215Y-370022D01*
X253201Y-370014D01*
X253193Y-370011D01*
X253189D01*
X253267Y-369678D01*
X253334Y-369700D01*
X253393Y-369722D01*
X253448Y-369752D01*
X253504Y-369777D01*
X253552Y-369807D01*
X253596Y-369840D01*
X253641Y-369870D01*
X253678Y-369900D01*
X253707Y-369929D01*
X253737Y-369955D01*
X253763Y-369981D01*
X253781Y-370000D01*
X253800Y-370018D01*
X253811Y-370033D01*
X253815Y-370040D01*
X253818Y-370044D01*
X253852Y-370096D01*
X253885Y-370147D01*
X253911Y-370199D01*
X253933Y-370255D01*
X253966Y-370366D01*
X253989Y-370466D01*
X254000Y-370514D01*
X254003Y-370554D01*
X254007Y-370595D01*
X254011Y-370628D01*
X254014Y-370654D01*
Y-370691D01*
X254007Y-370813D01*
X253989Y-370932D01*
X253966Y-371036D01*
X253952Y-371084D01*
X253937Y-371128D01*
X253922Y-371169D01*
X253907Y-371206D01*
X253896Y-371235D01*
X253885Y-371265D01*
X253874Y-371283D01*
X253866Y-371298D01*
X253863Y-371309D01*
X253859Y-371313D01*
X253796Y-371413D01*
X253722Y-371498D01*
X253648Y-371572D01*
X253574Y-371635D01*
X253507Y-371683D01*
X253478Y-371702D01*
X253452Y-371716D01*
X253434Y-371731D01*
X253419Y-371739D01*
X253408Y-371742D01*
X253404Y-371746D01*
X253289Y-371798D01*
X253171Y-371835D01*
X253052Y-371861D01*
X252945Y-371879D01*
X252897Y-371886D01*
X252849Y-371890D01*
X252812Y-371894D01*
X252775D01*
X252749Y-371898D01*
X252727D01*
X252712D01*
X252708D01*
X252575Y-371890D01*
X252446Y-371875D01*
X252331Y-371857D01*
X252275Y-371842D01*
X252227Y-371831D01*
X252183Y-371820D01*
X252142Y-371805D01*
X252105Y-371794D01*
X252076Y-371787D01*
X252053Y-371776D01*
X252035Y-371772D01*
X252024Y-371764D01*
X252020D01*
X251909Y-371709D01*
X251809Y-371646D01*
X251724Y-371579D01*
X251691Y-371546D01*
X251658Y-371516D01*
X251628Y-371487D01*
X251602Y-371457D01*
X251580Y-371431D01*
X251565Y-371409D01*
X251550Y-371394D01*
X251539Y-371380D01*
X251535Y-371372D01*
X251532Y-371369D01*
X251502Y-371317D01*
X251476Y-371265D01*
X251436Y-371154D01*
X251406Y-371043D01*
X251387Y-370936D01*
X251380Y-370884D01*
X251373Y-370839D01*
X251369Y-370799D01*
Y-370765D01*
X251365Y-370736D01*
Y-370695D01*
X251369Y-370621D01*
X251376Y-370551D01*
X251384Y-370484D01*
X251398Y-370421D01*
X251417Y-370362D01*
X251436Y-370307D01*
X251454Y-370255D01*
X251476Y-370207D01*
X251495Y-370166D01*
X251513Y-370125D01*
X251532Y-370096D01*
X251550Y-370066D01*
X251565Y-370048D01*
X251572Y-370029D01*
X251580Y-370022D01*
X251584Y-370018D01*
X251628Y-369966D01*
X251672Y-369922D01*
X251724Y-369881D01*
X251776Y-369840D01*
X251880Y-369774D01*
X251983Y-369722D01*
X252031Y-369700D01*
X252076Y-369681D01*
X252116Y-369667D01*
X252150Y-369655D01*
X252179Y-369644D01*
X252202Y-369637D01*
X252216Y-369633D01*
X252220D01*
X252305Y-369974D01*
D02*
G37*
G36*
X258232Y-377940D02*
X258169Y-377977D01*
X258110Y-378017D01*
X258051Y-378065D01*
X257999Y-378110D01*
X257955Y-378154D01*
X257918Y-378188D01*
X257907Y-378202D01*
X257896Y-378214D01*
X257892Y-378217D01*
X257888Y-378221D01*
X257825Y-378299D01*
X257766Y-378376D01*
X257714Y-378450D01*
X257674Y-378524D01*
X257636Y-378587D01*
X257622Y-378613D01*
X257611Y-378635D01*
X257599Y-378654D01*
X257596Y-378669D01*
X257589Y-378676D01*
Y-378680D01*
X257285D01*
X257307Y-378624D01*
X257333Y-378569D01*
X257359Y-378513D01*
X257385Y-378461D01*
X257407Y-378417D01*
X257426Y-378380D01*
X257440Y-378358D01*
X257444Y-378354D01*
Y-378350D01*
X257485Y-378284D01*
X257526Y-378225D01*
X257563Y-378173D01*
X257596Y-378132D01*
X257622Y-378095D01*
X257644Y-378073D01*
X257659Y-378054D01*
X257662Y-378051D01*
X255661D01*
Y-377736D01*
X258232D01*
Y-377940D01*
D02*
G37*
G36*
X256593Y-379216D02*
X256656Y-379224D01*
X256719Y-379235D01*
X256774Y-379250D01*
X256826Y-379268D01*
X256878Y-379287D01*
X256922Y-379309D01*
X256963Y-379327D01*
X257000Y-379349D01*
X257033Y-379372D01*
X257059Y-379390D01*
X257085Y-379409D01*
X257104Y-379423D01*
X257115Y-379434D01*
X257122Y-379442D01*
X257126Y-379446D01*
X257167Y-379490D01*
X257204Y-379534D01*
X257233Y-379583D01*
X257259Y-379631D01*
X257285Y-379679D01*
X257304Y-379727D01*
X257329Y-379816D01*
X257341Y-379856D01*
X257348Y-379893D01*
X257352Y-379927D01*
X257355Y-379956D01*
X257359Y-379978D01*
Y-380060D01*
X257352Y-380104D01*
X257333Y-380193D01*
X257307Y-380274D01*
X257278Y-380348D01*
X257248Y-380408D01*
X257233Y-380434D01*
X257222Y-380456D01*
X257211Y-380474D01*
X257204Y-380485D01*
X257200Y-380493D01*
X257196Y-380496D01*
X257888Y-380360D01*
Y-379335D01*
X258188D01*
Y-380607D01*
X256871Y-380855D01*
X256830Y-380559D01*
X256871Y-380533D01*
X256904Y-380500D01*
X256937Y-380470D01*
X256963Y-380441D01*
X256982Y-380411D01*
X257000Y-380389D01*
X257008Y-380374D01*
X257011Y-380371D01*
X257033Y-380323D01*
X257052Y-380274D01*
X257063Y-380230D01*
X257074Y-380186D01*
X257078Y-380149D01*
X257082Y-380119D01*
Y-380049D01*
X257074Y-380004D01*
X257056Y-379927D01*
X257030Y-379860D01*
X257004Y-379801D01*
X256974Y-379756D01*
X256948Y-379723D01*
X256930Y-379705D01*
X256926Y-379697D01*
X256922D01*
X256859Y-379645D01*
X256793Y-379608D01*
X256723Y-379583D01*
X256652Y-379564D01*
X256593Y-379553D01*
X256567Y-379549D01*
X256545D01*
X256526Y-379545D01*
X256512D01*
X256504D01*
X256501D01*
X256449D01*
X256401Y-379553D01*
X256308Y-379571D01*
X256230Y-379597D01*
X256168Y-379623D01*
X256116Y-379653D01*
X256075Y-379679D01*
X256064Y-379690D01*
X256053Y-379697D01*
X256049Y-379701D01*
X256046Y-379705D01*
X256016Y-379734D01*
X255990Y-379764D01*
X255946Y-379830D01*
X255916Y-379893D01*
X255898Y-379956D01*
X255883Y-380008D01*
X255879Y-380052D01*
X255875Y-380067D01*
Y-380089D01*
X255879Y-380160D01*
X255894Y-380223D01*
X255912Y-380278D01*
X255935Y-380323D01*
X255957Y-380363D01*
X255975Y-380393D01*
X255990Y-380408D01*
X255994Y-380415D01*
X256046Y-380459D01*
X256101Y-380496D01*
X256164Y-380526D01*
X256220Y-380548D01*
X256275Y-380563D01*
X256316Y-380574D01*
X256334Y-380578D01*
X256345Y-380581D01*
X256353D01*
X256356D01*
X256330Y-380911D01*
X256271Y-380903D01*
X256216Y-380892D01*
X256112Y-380859D01*
X256023Y-380818D01*
X255983Y-380796D01*
X255949Y-380774D01*
X255916Y-380755D01*
X255887Y-380733D01*
X255864Y-380715D01*
X255846Y-380696D01*
X255831Y-380681D01*
X255816Y-380674D01*
X255812Y-380667D01*
X255809Y-380663D01*
X255775Y-380619D01*
X255746Y-380574D01*
X255720Y-380526D01*
X255698Y-380478D01*
X255664Y-380385D01*
X255642Y-380293D01*
X255631Y-380252D01*
X255627Y-380211D01*
X255624Y-380178D01*
X255620Y-380149D01*
X255616Y-380123D01*
Y-380089D01*
X255620Y-380012D01*
X255631Y-379938D01*
X255646Y-379867D01*
X255664Y-379804D01*
X255690Y-379745D01*
X255716Y-379690D01*
X255742Y-379638D01*
X255772Y-379594D01*
X255801Y-379553D01*
X255827Y-379516D01*
X255857Y-379486D01*
X255879Y-379460D01*
X255898Y-379442D01*
X255912Y-379427D01*
X255924Y-379420D01*
X255927Y-379416D01*
X255975Y-379379D01*
X256027Y-379349D01*
X256075Y-379320D01*
X256127Y-379298D01*
X256227Y-379261D01*
X256323Y-379238D01*
X256364Y-379231D01*
X256404Y-379224D01*
X256438Y-379220D01*
X256467Y-379216D01*
X256493Y-379212D01*
X256512D01*
X256523D01*
X256526D01*
X256593Y-379216D01*
D02*
G37*
G36*
X256556Y-381540D02*
X256497Y-381555D01*
X256441Y-381573D01*
X256390Y-381592D01*
X256342Y-381610D01*
X256297Y-381632D01*
X256260Y-381655D01*
X256223Y-381680D01*
X256190Y-381703D01*
X256160Y-381721D01*
X256138Y-381743D01*
X256116Y-381762D01*
X256097Y-381777D01*
X256086Y-381791D01*
X256075Y-381803D01*
X256071Y-381806D01*
X256068Y-381810D01*
X256038Y-381847D01*
X256016Y-381888D01*
X255975Y-381969D01*
X255946Y-382047D01*
X255927Y-382124D01*
X255912Y-382191D01*
X255909Y-382217D01*
Y-382243D01*
X255905Y-382265D01*
Y-382291D01*
X255909Y-382376D01*
X255924Y-382457D01*
X255942Y-382531D01*
X255964Y-382598D01*
X255986Y-382650D01*
X255997Y-382672D01*
X256005Y-382691D01*
X256012Y-382705D01*
X256020Y-382716D01*
X256023Y-382724D01*
Y-382728D01*
X256075Y-382798D01*
X256131Y-382857D01*
X256194Y-382909D01*
X256253Y-382949D01*
X256305Y-382983D01*
X256349Y-383005D01*
X256367Y-383012D01*
X256379Y-383020D01*
X256386Y-383024D01*
X256390D01*
X256486Y-383053D01*
X256582Y-383075D01*
X256678Y-383094D01*
X256767Y-383105D01*
X256808Y-383109D01*
X256845Y-383112D01*
X256878D01*
X256904Y-383116D01*
X256926D01*
X256945D01*
X256956D01*
X256960D01*
X257056Y-383112D01*
X257144Y-383105D01*
X257226Y-383090D01*
X257300Y-383075D01*
X257363Y-383064D01*
X257389Y-383057D01*
X257411Y-383049D01*
X257429Y-383046D01*
X257440Y-383042D01*
X257448Y-383038D01*
X257452D01*
X257537Y-383001D01*
X257614Y-382961D01*
X257677Y-382916D01*
X257733Y-382868D01*
X257777Y-382827D01*
X257807Y-382794D01*
X257825Y-382768D01*
X257833Y-382765D01*
Y-382761D01*
X257881Y-382683D01*
X257918Y-382598D01*
X257944Y-382517D01*
X257958Y-382439D01*
X257969Y-382369D01*
X257973Y-382339D01*
Y-382313D01*
X257977Y-382295D01*
Y-382265D01*
X257973Y-382172D01*
X257958Y-382087D01*
X257936Y-382017D01*
X257914Y-381954D01*
X257888Y-381906D01*
X257870Y-381869D01*
X257855Y-381847D01*
X257847Y-381839D01*
X257792Y-381780D01*
X257729Y-381725D01*
X257662Y-381680D01*
X257596Y-381643D01*
X257537Y-381614D01*
X257507Y-381603D01*
X257485Y-381595D01*
X257466Y-381588D01*
X257452Y-381580D01*
X257444Y-381577D01*
X257440D01*
X257518Y-381244D01*
X257585Y-381266D01*
X257644Y-381288D01*
X257699Y-381318D01*
X257755Y-381344D01*
X257803Y-381373D01*
X257847Y-381407D01*
X257892Y-381436D01*
X257929Y-381466D01*
X257958Y-381495D01*
X257988Y-381521D01*
X258014Y-381547D01*
X258032Y-381566D01*
X258051Y-381584D01*
X258062Y-381599D01*
X258066Y-381606D01*
X258069Y-381610D01*
X258103Y-381662D01*
X258136Y-381714D01*
X258162Y-381766D01*
X258184Y-381821D01*
X258218Y-381932D01*
X258240Y-382032D01*
X258251Y-382080D01*
X258254Y-382121D01*
X258258Y-382161D01*
X258262Y-382195D01*
X258265Y-382221D01*
Y-382258D01*
X258258Y-382380D01*
X258240Y-382498D01*
X258218Y-382602D01*
X258203Y-382650D01*
X258188Y-382694D01*
X258173Y-382735D01*
X258158Y-382772D01*
X258147Y-382802D01*
X258136Y-382831D01*
X258125Y-382850D01*
X258118Y-382864D01*
X258114Y-382875D01*
X258110Y-382879D01*
X258047Y-382979D01*
X257973Y-383064D01*
X257899Y-383138D01*
X257825Y-383201D01*
X257759Y-383249D01*
X257729Y-383268D01*
X257703Y-383282D01*
X257685Y-383297D01*
X257670Y-383305D01*
X257659Y-383308D01*
X257655Y-383312D01*
X257540Y-383364D01*
X257422Y-383401D01*
X257304Y-383427D01*
X257196Y-383445D01*
X257148Y-383453D01*
X257100Y-383456D01*
X257063Y-383460D01*
X257026D01*
X257000Y-383464D01*
X256978D01*
X256963D01*
X256960D01*
X256826Y-383456D01*
X256697Y-383442D01*
X256582Y-383423D01*
X256526Y-383408D01*
X256479Y-383397D01*
X256434Y-383386D01*
X256393Y-383371D01*
X256356Y-383360D01*
X256327Y-383353D01*
X256305Y-383342D01*
X256286Y-383338D01*
X256275Y-383331D01*
X256271D01*
X256160Y-383275D01*
X256060Y-383212D01*
X255975Y-383146D01*
X255942Y-383112D01*
X255909Y-383083D01*
X255879Y-383053D01*
X255853Y-383024D01*
X255831Y-382998D01*
X255816Y-382975D01*
X255801Y-382961D01*
X255790Y-382946D01*
X255786Y-382938D01*
X255783Y-382935D01*
X255753Y-382883D01*
X255727Y-382831D01*
X255687Y-382720D01*
X255657Y-382609D01*
X255639Y-382502D01*
X255631Y-382450D01*
X255624Y-382406D01*
X255620Y-382365D01*
Y-382332D01*
X255616Y-382302D01*
Y-382261D01*
X255620Y-382187D01*
X255627Y-382117D01*
X255635Y-382050D01*
X255650Y-381988D01*
X255668Y-381928D01*
X255687Y-381873D01*
X255705Y-381821D01*
X255727Y-381773D01*
X255746Y-381732D01*
X255764Y-381692D01*
X255783Y-381662D01*
X255801Y-381632D01*
X255816Y-381614D01*
X255823Y-381595D01*
X255831Y-381588D01*
X255835Y-381584D01*
X255879Y-381532D01*
X255924Y-381488D01*
X255975Y-381447D01*
X256027Y-381407D01*
X256131Y-381340D01*
X256234Y-381288D01*
X256282Y-381266D01*
X256327Y-381247D01*
X256367Y-381233D01*
X256401Y-381222D01*
X256430Y-381210D01*
X256453Y-381203D01*
X256467Y-381199D01*
X256471D01*
X256556Y-381540D01*
D02*
G37*
G36*
X267713Y-366934D02*
X267776Y-366890D01*
X267802Y-366867D01*
X267828Y-366849D01*
X267850Y-366830D01*
X267865Y-366816D01*
X267876Y-366805D01*
X267880Y-366801D01*
X267898Y-366782D01*
X267916Y-366760D01*
X267965Y-366708D01*
X268020Y-366649D01*
X268076Y-366586D01*
X268124Y-366527D01*
X268146Y-366501D01*
X268168Y-366479D01*
X268183Y-366460D01*
X268194Y-366446D01*
X268201Y-366438D01*
X268205Y-366435D01*
X268257Y-366375D01*
X268305Y-366316D01*
X268353Y-366264D01*
X268394Y-366216D01*
X268435Y-366172D01*
X268472Y-366135D01*
X268505Y-366098D01*
X268534Y-366068D01*
X268564Y-366039D01*
X268586Y-366017D01*
X268605Y-365998D01*
X268623Y-365980D01*
X268645Y-365961D01*
X268653Y-365954D01*
X268716Y-365902D01*
X268771Y-365857D01*
X268827Y-365820D01*
X268871Y-365791D01*
X268912Y-365769D01*
X268941Y-365754D01*
X268960Y-365746D01*
X268967Y-365743D01*
X269023Y-365721D01*
X269078Y-365706D01*
X269130Y-365691D01*
X269175Y-365684D01*
X269215Y-365680D01*
X269245Y-365676D01*
X269263D01*
X269271D01*
X269326Y-365680D01*
X269378Y-365687D01*
X269430Y-365695D01*
X269474Y-365709D01*
X269563Y-365746D01*
X269633Y-365783D01*
X269667Y-365806D01*
X269692Y-365824D01*
X269718Y-365843D01*
X269737Y-365861D01*
X269752Y-365876D01*
X269766Y-365883D01*
X269770Y-365891D01*
X269774Y-365894D01*
X269811Y-365935D01*
X269844Y-365980D01*
X269870Y-366028D01*
X269892Y-366076D01*
X269929Y-366172D01*
X269955Y-366268D01*
X269963Y-366309D01*
X269970Y-366350D01*
X269974Y-366387D01*
X269977Y-366416D01*
X269981Y-366442D01*
Y-366479D01*
X269977Y-366546D01*
X269974Y-366609D01*
X269963Y-366668D01*
X269952Y-366723D01*
X269937Y-366775D01*
X269922Y-366823D01*
X269903Y-366867D01*
X269885Y-366908D01*
X269866Y-366945D01*
X269848Y-366975D01*
X269833Y-367001D01*
X269818Y-367023D01*
X269807Y-367041D01*
X269796Y-367053D01*
X269792Y-367060D01*
X269789Y-367064D01*
X269752Y-367101D01*
X269711Y-367134D01*
X269667Y-367167D01*
X269622Y-367193D01*
X269533Y-367237D01*
X269445Y-367267D01*
X269404Y-367278D01*
X269363Y-367289D01*
X269330Y-367297D01*
X269300Y-367304D01*
X269274Y-367308D01*
X269256D01*
X269245Y-367312D01*
X269241D01*
X269208Y-366990D01*
X269293Y-366982D01*
X269367Y-366967D01*
X269433Y-366945D01*
X269485Y-366919D01*
X269530Y-366897D01*
X269559Y-366875D01*
X269578Y-366860D01*
X269585Y-366853D01*
X269630Y-366797D01*
X269663Y-366738D01*
X269689Y-366675D01*
X269704Y-366620D01*
X269715Y-366568D01*
X269718Y-366523D01*
X269722Y-366509D01*
Y-366486D01*
X269718Y-366409D01*
X269704Y-366338D01*
X269681Y-366279D01*
X269659Y-366227D01*
X269633Y-366187D01*
X269615Y-366161D01*
X269600Y-366142D01*
X269593Y-366135D01*
X269541Y-366090D01*
X269489Y-366057D01*
X269437Y-366031D01*
X269385Y-366017D01*
X269345Y-366005D01*
X269308Y-366002D01*
X269285Y-365998D01*
X269282D01*
X269278D01*
X269212Y-366005D01*
X269141Y-366020D01*
X269078Y-366046D01*
X269019Y-366072D01*
X268971Y-366102D01*
X268930Y-366127D01*
X268916Y-366135D01*
X268904Y-366142D01*
X268901Y-366150D01*
X268897D01*
X268856Y-366179D01*
X268816Y-366216D01*
X268771Y-366257D01*
X268727Y-366301D01*
X268638Y-366394D01*
X268549Y-366486D01*
X268509Y-366534D01*
X268472Y-366575D01*
X268438Y-366616D01*
X268409Y-366649D01*
X268386Y-366675D01*
X268368Y-366697D01*
X268357Y-366712D01*
X268353Y-366716D01*
X268275Y-366808D01*
X268201Y-366893D01*
X268135Y-366964D01*
X268079Y-367019D01*
X268031Y-367067D01*
X267998Y-367101D01*
X267976Y-367119D01*
X267972Y-367126D01*
X267968D01*
X267905Y-367178D01*
X267846Y-367219D01*
X267787Y-367256D01*
X267735Y-367286D01*
X267691Y-367308D01*
X267657Y-367323D01*
X267635Y-367330D01*
X267632Y-367334D01*
X267628D01*
X267587Y-367349D01*
X267550Y-367356D01*
X267513Y-367363D01*
X267480Y-367367D01*
X267450Y-367371D01*
X267428D01*
X267413D01*
X267410D01*
Y-365672D01*
X267713D01*
Y-366934D01*
D02*
G37*
G36*
X268342Y-367622D02*
X268405Y-367630D01*
X268468Y-367641D01*
X268523Y-367656D01*
X268575Y-367674D01*
X268627Y-367693D01*
X268671Y-367715D01*
X268712Y-367733D01*
X268749Y-367756D01*
X268782Y-367778D01*
X268808Y-367796D01*
X268834Y-367815D01*
X268853Y-367829D01*
X268864Y-367841D01*
X268871Y-367848D01*
X268875Y-367852D01*
X268916Y-367896D01*
X268952Y-367940D01*
X268982Y-367989D01*
X269008Y-368037D01*
X269034Y-368085D01*
X269052Y-368133D01*
X269078Y-368222D01*
X269089Y-368262D01*
X269097Y-368299D01*
X269100Y-368333D01*
X269104Y-368362D01*
X269108Y-368385D01*
Y-368466D01*
X269100Y-368510D01*
X269082Y-368599D01*
X269056Y-368681D01*
X269026Y-368755D01*
X268997Y-368814D01*
X268982Y-368840D01*
X268971Y-368862D01*
X268960Y-368880D01*
X268952Y-368891D01*
X268949Y-368899D01*
X268945Y-368902D01*
X269637Y-368766D01*
Y-367741D01*
X269937D01*
Y-369014D01*
X268619Y-369261D01*
X268579Y-368965D01*
X268619Y-368939D01*
X268653Y-368906D01*
X268686Y-368877D01*
X268712Y-368847D01*
X268730Y-368817D01*
X268749Y-368795D01*
X268756Y-368780D01*
X268760Y-368777D01*
X268782Y-368729D01*
X268801Y-368681D01*
X268812Y-368636D01*
X268823Y-368592D01*
X268827Y-368555D01*
X268830Y-368525D01*
Y-368455D01*
X268823Y-368410D01*
X268805Y-368333D01*
X268779Y-368266D01*
X268753Y-368207D01*
X268723Y-368162D01*
X268697Y-368129D01*
X268679Y-368111D01*
X268675Y-368103D01*
X268671D01*
X268608Y-368052D01*
X268542Y-368015D01*
X268472Y-367989D01*
X268401Y-367970D01*
X268342Y-367959D01*
X268316Y-367955D01*
X268294D01*
X268275Y-367952D01*
X268261D01*
X268253D01*
X268250D01*
X268198D01*
X268150Y-367959D01*
X268057Y-367977D01*
X267979Y-368003D01*
X267916Y-368029D01*
X267865Y-368059D01*
X267824Y-368085D01*
X267813Y-368096D01*
X267802Y-368103D01*
X267798Y-368107D01*
X267794Y-368111D01*
X267765Y-368140D01*
X267739Y-368170D01*
X267694Y-368236D01*
X267665Y-368299D01*
X267646Y-368362D01*
X267632Y-368414D01*
X267628Y-368459D01*
X267624Y-368473D01*
Y-368495D01*
X267628Y-368566D01*
X267643Y-368629D01*
X267661Y-368684D01*
X267683Y-368729D01*
X267706Y-368769D01*
X267724Y-368799D01*
X267739Y-368814D01*
X267743Y-368821D01*
X267794Y-368865D01*
X267850Y-368902D01*
X267913Y-368932D01*
X267968Y-368954D01*
X268024Y-368969D01*
X268064Y-368980D01*
X268083Y-368984D01*
X268094Y-368988D01*
X268102D01*
X268105D01*
X268079Y-369317D01*
X268020Y-369309D01*
X267965Y-369298D01*
X267861Y-369265D01*
X267772Y-369224D01*
X267731Y-369202D01*
X267698Y-369180D01*
X267665Y-369162D01*
X267635Y-369139D01*
X267613Y-369121D01*
X267595Y-369102D01*
X267580Y-369088D01*
X267565Y-369080D01*
X267561Y-369073D01*
X267558Y-369069D01*
X267524Y-369025D01*
X267495Y-368980D01*
X267469Y-368932D01*
X267447Y-368884D01*
X267413Y-368792D01*
X267391Y-368699D01*
X267380Y-368658D01*
X267376Y-368618D01*
X267373Y-368584D01*
X267369Y-368555D01*
X267365Y-368529D01*
Y-368495D01*
X267369Y-368418D01*
X267380Y-368344D01*
X267395Y-368273D01*
X267413Y-368211D01*
X267439Y-368151D01*
X267465Y-368096D01*
X267491Y-368044D01*
X267521Y-368000D01*
X267550Y-367959D01*
X267576Y-367922D01*
X267606Y-367892D01*
X267628Y-367866D01*
X267646Y-367848D01*
X267661Y-367833D01*
X267672Y-367826D01*
X267676Y-367822D01*
X267724Y-367785D01*
X267776Y-367756D01*
X267824Y-367726D01*
X267876Y-367704D01*
X267976Y-367667D01*
X268072Y-367645D01*
X268113Y-367637D01*
X268153Y-367630D01*
X268187Y-367626D01*
X268216Y-367622D01*
X268242Y-367619D01*
X268261D01*
X268272D01*
X268275D01*
X268342Y-367622D01*
D02*
G37*
G36*
X268305Y-369946D02*
X268246Y-369961D01*
X268190Y-369979D01*
X268139Y-369998D01*
X268090Y-370016D01*
X268046Y-370038D01*
X268009Y-370061D01*
X267972Y-370087D01*
X267939Y-370109D01*
X267909Y-370127D01*
X267887Y-370149D01*
X267865Y-370168D01*
X267846Y-370183D01*
X267835Y-370198D01*
X267824Y-370209D01*
X267820Y-370212D01*
X267817Y-370216D01*
X267787Y-370253D01*
X267765Y-370294D01*
X267724Y-370375D01*
X267694Y-370453D01*
X267676Y-370531D01*
X267661Y-370597D01*
X267657Y-370623D01*
Y-370649D01*
X267654Y-370671D01*
Y-370697D01*
X267657Y-370782D01*
X267672Y-370864D01*
X267691Y-370937D01*
X267713Y-371004D01*
X267735Y-371056D01*
X267746Y-371078D01*
X267754Y-371097D01*
X267761Y-371111D01*
X267769Y-371123D01*
X267772Y-371130D01*
Y-371134D01*
X267824Y-371204D01*
X267880Y-371263D01*
X267942Y-371315D01*
X268002Y-371356D01*
X268053Y-371389D01*
X268098Y-371411D01*
X268116Y-371418D01*
X268127Y-371426D01*
X268135Y-371430D01*
X268139D01*
X268235Y-371459D01*
X268331Y-371481D01*
X268427Y-371500D01*
X268516Y-371511D01*
X268557Y-371515D01*
X268594Y-371518D01*
X268627D01*
X268653Y-371522D01*
X268675D01*
X268693D01*
X268705D01*
X268708D01*
X268805Y-371518D01*
X268893Y-371511D01*
X268975Y-371496D01*
X269049Y-371481D01*
X269112Y-371470D01*
X269138Y-371463D01*
X269160Y-371456D01*
X269178Y-371452D01*
X269189Y-371448D01*
X269197Y-371444D01*
X269200D01*
X269285Y-371407D01*
X269363Y-371367D01*
X269426Y-371322D01*
X269482Y-371274D01*
X269526Y-371234D01*
X269556Y-371200D01*
X269574Y-371174D01*
X269582Y-371171D01*
Y-371167D01*
X269630Y-371089D01*
X269667Y-371004D01*
X269692Y-370923D01*
X269707Y-370845D01*
X269718Y-370775D01*
X269722Y-370745D01*
Y-370719D01*
X269726Y-370701D01*
Y-370671D01*
X269722Y-370579D01*
X269707Y-370494D01*
X269685Y-370423D01*
X269663Y-370360D01*
X269637Y-370312D01*
X269619Y-370275D01*
X269604Y-370253D01*
X269596Y-370246D01*
X269541Y-370186D01*
X269478Y-370131D01*
X269411Y-370087D01*
X269345Y-370050D01*
X269285Y-370020D01*
X269256Y-370009D01*
X269234Y-370001D01*
X269215Y-369994D01*
X269200Y-369987D01*
X269193Y-369983D01*
X269189D01*
X269267Y-369650D01*
X269334Y-369672D01*
X269393Y-369694D01*
X269448Y-369724D01*
X269504Y-369750D01*
X269552Y-369779D01*
X269596Y-369813D01*
X269641Y-369842D01*
X269678Y-369872D01*
X269707Y-369901D01*
X269737Y-369927D01*
X269763Y-369953D01*
X269781Y-369972D01*
X269800Y-369990D01*
X269811Y-370005D01*
X269815Y-370012D01*
X269818Y-370016D01*
X269852Y-370068D01*
X269885Y-370120D01*
X269911Y-370172D01*
X269933Y-370227D01*
X269966Y-370338D01*
X269988Y-370438D01*
X270000Y-370486D01*
X270003Y-370527D01*
X270007Y-370567D01*
X270011Y-370601D01*
X270014Y-370627D01*
Y-370664D01*
X270007Y-370786D01*
X269988Y-370904D01*
X269966Y-371008D01*
X269952Y-371056D01*
X269937Y-371100D01*
X269922Y-371141D01*
X269907Y-371178D01*
X269896Y-371208D01*
X269885Y-371237D01*
X269874Y-371256D01*
X269866Y-371270D01*
X269863Y-371282D01*
X269859Y-371285D01*
X269796Y-371385D01*
X269722Y-371470D01*
X269648Y-371544D01*
X269574Y-371607D01*
X269508Y-371655D01*
X269478Y-371674D01*
X269452Y-371689D01*
X269433Y-371703D01*
X269419Y-371711D01*
X269408Y-371714D01*
X269404Y-371718D01*
X269289Y-371770D01*
X269171Y-371807D01*
X269052Y-371833D01*
X268945Y-371851D01*
X268897Y-371859D01*
X268849Y-371863D01*
X268812Y-371866D01*
X268775D01*
X268749Y-371870D01*
X268727D01*
X268712D01*
X268708D01*
X268575Y-371863D01*
X268446Y-371848D01*
X268331Y-371829D01*
X268275Y-371814D01*
X268227Y-371803D01*
X268183Y-371792D01*
X268142Y-371777D01*
X268105Y-371766D01*
X268076Y-371759D01*
X268053Y-371748D01*
X268035Y-371744D01*
X268024Y-371737D01*
X268020D01*
X267909Y-371681D01*
X267809Y-371618D01*
X267724Y-371552D01*
X267691Y-371518D01*
X267657Y-371489D01*
X267628Y-371459D01*
X267602Y-371430D01*
X267580Y-371404D01*
X267565Y-371381D01*
X267550Y-371367D01*
X267539Y-371352D01*
X267535Y-371344D01*
X267532Y-371341D01*
X267502Y-371289D01*
X267476Y-371237D01*
X267436Y-371126D01*
X267406Y-371015D01*
X267387Y-370908D01*
X267380Y-370856D01*
X267373Y-370812D01*
X267369Y-370771D01*
Y-370738D01*
X267365Y-370708D01*
Y-370667D01*
X267369Y-370593D01*
X267376Y-370523D01*
X267384Y-370457D01*
X267399Y-370394D01*
X267417Y-370334D01*
X267436Y-370279D01*
X267454Y-370227D01*
X267476Y-370179D01*
X267495Y-370138D01*
X267513Y-370098D01*
X267532Y-370068D01*
X267550Y-370038D01*
X267565Y-370020D01*
X267572Y-370001D01*
X267580Y-369994D01*
X267583Y-369990D01*
X267628Y-369938D01*
X267672Y-369894D01*
X267724Y-369853D01*
X267776Y-369813D01*
X267880Y-369746D01*
X267983Y-369694D01*
X268031Y-369672D01*
X268076Y-369654D01*
X268116Y-369639D01*
X268150Y-369628D01*
X268179Y-369617D01*
X268201Y-369609D01*
X268216Y-369605D01*
X268220D01*
X268305Y-369946D01*
D02*
G37*
%LPC*%
G36*
X288607Y-273764D02*
X287845D01*
Y-274612D01*
X288651D01*
X288751Y-274608D01*
X288836Y-274593D01*
X288910Y-274575D01*
X288966Y-274553D01*
X289014Y-274530D01*
X289043Y-274512D01*
X289062Y-274497D01*
X289069Y-274493D01*
X289114Y-274445D01*
X289147Y-274397D01*
X289169Y-274345D01*
X289188Y-274301D01*
X289195Y-274257D01*
X289199Y-274223D01*
X289202Y-274201D01*
Y-274197D01*
Y-274194D01*
X289199Y-274149D01*
X289191Y-274105D01*
X289180Y-274068D01*
X289169Y-274035D01*
X289154Y-274005D01*
X289143Y-273983D01*
X289136Y-273968D01*
X289132Y-273964D01*
X289106Y-273927D01*
X289073Y-273894D01*
X289040Y-273868D01*
X289006Y-273846D01*
X288977Y-273831D01*
X288955Y-273820D01*
X288940Y-273813D01*
X288932Y-273809D01*
X288881Y-273794D01*
X288821Y-273783D01*
X288762Y-273776D01*
X288703Y-273772D01*
X288651Y-273768D01*
X288607Y-273764D01*
D02*
G37*
G36*
X142671Y-347737D02*
X141864D01*
Y-348585D01*
X142627D01*
X142671Y-348581D01*
X142723Y-348577D01*
X142782Y-348573D01*
X142841Y-348566D01*
X142900Y-348555D01*
X142952Y-348540D01*
X142959Y-348536D01*
X142974Y-348529D01*
X142997Y-348518D01*
X143026Y-348503D01*
X143059Y-348481D01*
X143093Y-348455D01*
X143126Y-348422D01*
X143152Y-348385D01*
X143156Y-348381D01*
X143163Y-348366D01*
X143174Y-348344D01*
X143189Y-348314D01*
X143200Y-348281D01*
X143211Y-348244D01*
X143219Y-348200D01*
X143222Y-348155D01*
Y-348152D01*
Y-348148D01*
X143219Y-348126D01*
X143215Y-348093D01*
X143207Y-348048D01*
X143189Y-348004D01*
X143167Y-347952D01*
X143133Y-347904D01*
X143089Y-347856D01*
X143082Y-347852D01*
X143063Y-347837D01*
X143034Y-347819D01*
X142985Y-347797D01*
X142930Y-347774D01*
X142856Y-347756D01*
X142771Y-347741D01*
X142671Y-347737D01*
D02*
G37*
G36*
X146987Y-352360D02*
X146180Y-353507D01*
X146987D01*
Y-352360D01*
D02*
G37*
G36*
X142687Y-352135D02*
X141881D01*
Y-352982D01*
X142643D01*
X142687Y-352978D01*
X142739Y-352975D01*
X142798Y-352971D01*
X142858Y-352963D01*
X142917Y-352952D01*
X142969Y-352938D01*
X142976Y-352934D01*
X142991Y-352926D01*
X143013Y-352915D01*
X143043Y-352901D01*
X143076Y-352878D01*
X143109Y-352852D01*
X143143Y-352819D01*
X143168Y-352782D01*
X143172Y-352778D01*
X143180Y-352764D01*
X143191Y-352741D01*
X143205Y-352712D01*
X143217Y-352678D01*
X143228Y-352642D01*
X143235Y-352597D01*
X143239Y-352553D01*
Y-352549D01*
Y-352545D01*
X143235Y-352523D01*
X143231Y-352490D01*
X143224Y-352445D01*
X143205Y-352401D01*
X143183Y-352349D01*
X143150Y-352301D01*
X143106Y-352253D01*
X143098Y-352249D01*
X143080Y-352235D01*
X143050Y-352216D01*
X143002Y-352194D01*
X142947Y-352172D01*
X142873Y-352153D01*
X142787Y-352138D01*
X142687Y-352135D01*
D02*
G37*
G36*
X422817Y-354833D02*
X422225D01*
Y-356787D01*
X422832D01*
X422858Y-356783D01*
X422914Y-356780D01*
X422976Y-356776D01*
X423043Y-356768D01*
X423110Y-356757D01*
X423165Y-356743D01*
X423173Y-356739D01*
X423191Y-356735D01*
X423217Y-356724D01*
X423250Y-356709D01*
X423287Y-356687D01*
X423324Y-356665D01*
X423361Y-356639D01*
X423398Y-356609D01*
X423402Y-356602D01*
X423417Y-356587D01*
X423439Y-356561D01*
X423465Y-356524D01*
X423494Y-356476D01*
X423528Y-356421D01*
X423557Y-356358D01*
X423583Y-356288D01*
Y-356284D01*
X423587Y-356276D01*
X423591Y-356265D01*
X423594Y-356251D01*
X423598Y-356232D01*
X423605Y-356206D01*
X423613Y-356180D01*
X423620Y-356151D01*
X423631Y-356077D01*
X423642Y-355992D01*
X423650Y-355895D01*
X423654Y-355792D01*
Y-355788D01*
Y-355773D01*
Y-355755D01*
X423650Y-355725D01*
Y-355692D01*
X423646Y-355655D01*
X423642Y-355610D01*
X423639Y-355566D01*
X423620Y-355466D01*
X423598Y-355363D01*
X423565Y-355266D01*
X423543Y-355218D01*
X423520Y-355177D01*
Y-355174D01*
X423513Y-355166D01*
X423506Y-355155D01*
X423498Y-355140D01*
X423469Y-355103D01*
X423432Y-355059D01*
X423384Y-355011D01*
X423328Y-354963D01*
X423265Y-354922D01*
X423199Y-354889D01*
X423191Y-354885D01*
X423173Y-354882D01*
X423139Y-354870D01*
X423091Y-354859D01*
X423032Y-354852D01*
X422958Y-354841D01*
X422914Y-354837D01*
X422865D01*
X422817Y-354833D01*
D02*
G37*
G36*
X469989Y-356500D02*
X469967D01*
X469952Y-356503D01*
X469915Y-356507D01*
X469863Y-356518D01*
X469808Y-356537D01*
X469745Y-356566D01*
X469686Y-356603D01*
X469627Y-356655D01*
X469619Y-356662D01*
X469604Y-356681D01*
X469579Y-356714D01*
X469553Y-356762D01*
X469527Y-356818D01*
X469501Y-356888D01*
X469486Y-356966D01*
X469479Y-357055D01*
Y-357062D01*
Y-357081D01*
X469482Y-357114D01*
X469486Y-357154D01*
X469493Y-357203D01*
X469508Y-357254D01*
X469523Y-357310D01*
X469545Y-357365D01*
X469549Y-357373D01*
X469560Y-357391D01*
X469575Y-357417D01*
X469597Y-357451D01*
X469623Y-357484D01*
X469656Y-357524D01*
X469693Y-357558D01*
X469738Y-357591D01*
X469745Y-357595D01*
X469760Y-357602D01*
X469786Y-357617D01*
X469819Y-357628D01*
X469856Y-357643D01*
X469900Y-357658D01*
X469948Y-357665D01*
X470000Y-357669D01*
X470019D01*
X470034Y-357665D01*
X470071Y-357661D01*
X470119Y-357650D01*
X470170Y-357628D01*
X470230Y-357602D01*
X470289Y-357561D01*
X470319Y-357539D01*
X470344Y-357510D01*
Y-357506D01*
X470352Y-357502D01*
X470367Y-357480D01*
X470389Y-357443D01*
X470418Y-357395D01*
X470444Y-357332D01*
X470467Y-357258D01*
X470481Y-357173D01*
X470489Y-357073D01*
Y-357069D01*
Y-357062D01*
Y-357047D01*
X470485Y-357029D01*
Y-357006D01*
X470481Y-356980D01*
X470470Y-356921D01*
X470455Y-356855D01*
X470430Y-356785D01*
X470393Y-356718D01*
X470344Y-356655D01*
X470337Y-356648D01*
X470319Y-356629D01*
X470289Y-356607D01*
X470248Y-356577D01*
X470196Y-356548D01*
X470137Y-356525D01*
X470067Y-356507D01*
X469989Y-356500D01*
D02*
G37*
G36*
X467610Y-355626D02*
X467018D01*
Y-357580D01*
X467625D01*
X467651Y-357576D01*
X467706Y-357573D01*
X467769Y-357569D01*
X467836Y-357561D01*
X467902Y-357550D01*
X467958Y-357536D01*
X467965Y-357532D01*
X467984Y-357528D01*
X468010Y-357517D01*
X468043Y-357502D01*
X468080Y-357480D01*
X468117Y-357458D01*
X468154Y-357432D01*
X468191Y-357402D01*
X468195Y-357395D01*
X468210Y-357380D01*
X468232Y-357354D01*
X468258Y-357317D01*
X468287Y-357269D01*
X468321Y-357214D01*
X468350Y-357151D01*
X468376Y-357081D01*
Y-357077D01*
X468380Y-357069D01*
X468383Y-357058D01*
X468387Y-357043D01*
X468391Y-357025D01*
X468398Y-356999D01*
X468406Y-356973D01*
X468413Y-356944D01*
X468424Y-356870D01*
X468435Y-356785D01*
X468443Y-356688D01*
X468446Y-356585D01*
Y-356581D01*
Y-356566D01*
Y-356548D01*
X468443Y-356518D01*
Y-356485D01*
X468439Y-356448D01*
X468435Y-356403D01*
X468432Y-356359D01*
X468413Y-356259D01*
X468391Y-356155D01*
X468358Y-356059D01*
X468335Y-356011D01*
X468313Y-355970D01*
Y-355967D01*
X468306Y-355959D01*
X468298Y-355948D01*
X468291Y-355933D01*
X468261Y-355896D01*
X468224Y-355852D01*
X468176Y-355804D01*
X468121Y-355756D01*
X468058Y-355715D01*
X467991Y-355682D01*
X467984Y-355678D01*
X467965Y-355674D01*
X467932Y-355663D01*
X467884Y-355652D01*
X467825Y-355645D01*
X467751Y-355634D01*
X467706Y-355630D01*
X467658D01*
X467610Y-355626D01*
D02*
G37*
G36*
X506030Y-355303D02*
X505438D01*
Y-357256D01*
X506044D01*
X506070Y-357253D01*
X506126Y-357249D01*
X506189Y-357245D01*
X506255Y-357238D01*
X506322Y-357227D01*
X506377Y-357212D01*
X506385Y-357208D01*
X506403Y-357205D01*
X506429Y-357193D01*
X506462Y-357179D01*
X506499Y-357156D01*
X506536Y-357134D01*
X506573Y-357108D01*
X506610Y-357079D01*
X506614Y-357071D01*
X506629Y-357057D01*
X506651Y-357031D01*
X506677Y-356994D01*
X506707Y-356946D01*
X506740Y-356890D01*
X506770Y-356827D01*
X506795Y-356757D01*
Y-356753D01*
X506799Y-356746D01*
X506803Y-356735D01*
X506807Y-356720D01*
X506810Y-356701D01*
X506818Y-356676D01*
X506825Y-356650D01*
X506832Y-356620D01*
X506844Y-356546D01*
X506855Y-356461D01*
X506862Y-356365D01*
X506866Y-356261D01*
Y-356257D01*
Y-356243D01*
Y-356224D01*
X506862Y-356194D01*
Y-356161D01*
X506858Y-356124D01*
X506855Y-356080D01*
X506851Y-356035D01*
X506832Y-355936D01*
X506810Y-355832D01*
X506777Y-355736D01*
X506755Y-355688D01*
X506733Y-355647D01*
Y-355643D01*
X506725Y-355636D01*
X506718Y-355625D01*
X506710Y-355610D01*
X506681Y-355573D01*
X506644Y-355528D01*
X506596Y-355480D01*
X506540Y-355432D01*
X506477Y-355392D01*
X506411Y-355358D01*
X506403Y-355355D01*
X506385Y-355351D01*
X506351Y-355340D01*
X506303Y-355329D01*
X506244Y-355321D01*
X506170Y-355310D01*
X506126Y-355307D01*
X506078D01*
X506030Y-355303D01*
D02*
G37*
G36*
X508390Y-355247D02*
X508360D01*
X508327Y-355255D01*
X508283Y-355262D01*
X508235Y-355277D01*
X508183Y-355295D01*
X508135Y-355325D01*
X508087Y-355366D01*
X508083Y-355369D01*
X508068Y-355384D01*
X508050Y-355410D01*
X508031Y-355443D01*
X508009Y-355484D01*
X507991Y-355532D01*
X507976Y-355584D01*
X507972Y-355643D01*
Y-355647D01*
Y-355651D01*
X507976Y-355673D01*
X507979Y-355706D01*
X507987Y-355747D01*
X508002Y-355795D01*
X508020Y-355843D01*
X508050Y-355895D01*
X508087Y-355939D01*
X508090Y-355943D01*
X508109Y-355958D01*
X508135Y-355976D01*
X508168Y-355995D01*
X508213Y-356017D01*
X508264Y-356035D01*
X508323Y-356050D01*
X508390Y-356054D01*
X508397D01*
X508420Y-356050D01*
X508453Y-356047D01*
X508497Y-356039D01*
X508545Y-356024D01*
X508594Y-356006D01*
X508645Y-355976D01*
X508690Y-355939D01*
X508694Y-355936D01*
X508708Y-355917D01*
X508727Y-355895D01*
X508749Y-355861D01*
X508771Y-355821D01*
X508790Y-355773D01*
X508805Y-355717D01*
X508808Y-355658D01*
Y-355654D01*
Y-355651D01*
Y-355628D01*
X508801Y-355595D01*
X508793Y-355554D01*
X508779Y-355510D01*
X508756Y-355462D01*
X508727Y-355414D01*
X508686Y-355366D01*
X508682Y-355362D01*
X508664Y-355347D01*
X508638Y-355329D01*
X508605Y-355307D01*
X508560Y-355284D01*
X508512Y-355266D01*
X508453Y-355251D01*
X508390Y-355247D01*
D02*
G37*
G36*
X508379Y-356309D02*
X508357D01*
X508342Y-356313D01*
X508301Y-356317D01*
X508250Y-356328D01*
X508190Y-356346D01*
X508131Y-356372D01*
X508068Y-356409D01*
X508013Y-356457D01*
X508005Y-356465D01*
X507991Y-356483D01*
X507968Y-356516D01*
X507942Y-356557D01*
X507913Y-356613D01*
X507891Y-356676D01*
X507876Y-356746D01*
X507868Y-356823D01*
Y-356831D01*
Y-356846D01*
X507872Y-356872D01*
X507876Y-356905D01*
X507883Y-356946D01*
X507894Y-356990D01*
X507909Y-357034D01*
X507928Y-357083D01*
X507931Y-357086D01*
X507939Y-357105D01*
X507954Y-357127D01*
X507976Y-357153D01*
X508002Y-357186D01*
X508035Y-357219D01*
X508072Y-357249D01*
X508116Y-357279D01*
X508124Y-357282D01*
X508139Y-357290D01*
X508164Y-357301D01*
X508198Y-357312D01*
X508238Y-357323D01*
X508287Y-357334D01*
X508338Y-357342D01*
X508390Y-357345D01*
X508412D01*
X508427Y-357342D01*
X508471Y-357338D01*
X508523Y-357327D01*
X508582Y-357308D01*
X508645Y-357286D01*
X508705Y-357249D01*
X508764Y-357201D01*
X508771Y-357193D01*
X508786Y-357175D01*
X508812Y-357142D01*
X508838Y-357101D01*
X508864Y-357049D01*
X508890Y-356986D01*
X508904Y-356912D01*
X508912Y-356835D01*
Y-356831D01*
Y-356823D01*
Y-356812D01*
X508908Y-356798D01*
X508904Y-356757D01*
X508893Y-356701D01*
X508875Y-356646D01*
X508849Y-356583D01*
X508812Y-356520D01*
X508760Y-356461D01*
X508753Y-356453D01*
X508734Y-356439D01*
X508701Y-356413D01*
X508657Y-356383D01*
X508601Y-356357D01*
X508534Y-356331D01*
X508460Y-356317D01*
X508379Y-356309D01*
D02*
G37*
G36*
X551012Y-355123D02*
X550420D01*
Y-357076D01*
X551026D01*
X551052Y-357073D01*
X551108Y-357069D01*
X551171Y-357065D01*
X551237Y-357058D01*
X551304Y-357047D01*
X551359Y-357032D01*
X551367Y-357028D01*
X551385Y-357024D01*
X551411Y-357013D01*
X551444Y-356998D01*
X551481Y-356976D01*
X551518Y-356954D01*
X551555Y-356928D01*
X551592Y-356899D01*
X551596Y-356891D01*
X551611Y-356876D01*
X551633Y-356851D01*
X551659Y-356814D01*
X551689Y-356766D01*
X551722Y-356710D01*
X551752Y-356647D01*
X551778Y-356577D01*
Y-356573D01*
X551781Y-356566D01*
X551785Y-356555D01*
X551789Y-356540D01*
X551792Y-356521D01*
X551800Y-356495D01*
X551807Y-356469D01*
X551815Y-356440D01*
X551826Y-356366D01*
X551837Y-356281D01*
X551844Y-356185D01*
X551848Y-356081D01*
Y-356077D01*
Y-356062D01*
Y-356044D01*
X551844Y-356014D01*
Y-355981D01*
X551840Y-355944D01*
X551837Y-355900D01*
X551833Y-355855D01*
X551815Y-355755D01*
X551792Y-355652D01*
X551759Y-355556D01*
X551737Y-355507D01*
X551715Y-355467D01*
Y-355463D01*
X551707Y-355456D01*
X551700Y-355445D01*
X551692Y-355430D01*
X551663Y-355393D01*
X551626Y-355348D01*
X551578Y-355300D01*
X551522Y-355252D01*
X551459Y-355211D01*
X551393Y-355178D01*
X551385Y-355174D01*
X551367Y-355171D01*
X551334Y-355160D01*
X551285Y-355149D01*
X551226Y-355141D01*
X551152Y-355130D01*
X551108Y-355126D01*
X551060D01*
X551012Y-355123D01*
D02*
G37*
G36*
X207210Y-378156D02*
X206064D01*
Y-378963D01*
X207210Y-378156D01*
D02*
G37*
G36*
Y-380147D02*
X206064D01*
Y-380953D01*
X207210Y-380147D01*
D02*
G37*
G36*
X210459Y-368377D02*
X209312D01*
Y-369184D01*
X210459Y-368377D01*
D02*
G37*
G36*
X217897Y-377810D02*
X217882D01*
X217875D01*
X217871D01*
X217771Y-377818D01*
X217686Y-377832D01*
X217612Y-377855D01*
X217549Y-377881D01*
X217501Y-377910D01*
X217464Y-377932D01*
X217442Y-377947D01*
X217438Y-377955D01*
X217435D01*
X217405Y-377980D01*
X217383Y-378010D01*
X217342Y-378069D01*
X217316Y-378128D01*
X217294Y-378180D01*
X217283Y-378228D01*
X217279Y-378265D01*
X217275Y-378280D01*
Y-378299D01*
X217279Y-378350D01*
X217286Y-378398D01*
X217301Y-378443D01*
X217316Y-378480D01*
X217327Y-378513D01*
X217342Y-378539D01*
X217349Y-378554D01*
X217353Y-378561D01*
X217386Y-378606D01*
X217420Y-378643D01*
X217460Y-378676D01*
X217494Y-378702D01*
X217527Y-378724D01*
X217553Y-378739D01*
X217571Y-378750D01*
X217579Y-378754D01*
X217634Y-378776D01*
X217690Y-378791D01*
X217742Y-378805D01*
X217790Y-378813D01*
X217830Y-378817D01*
X217864Y-378820D01*
X217882D01*
X217890D01*
X217978Y-378813D01*
X218056Y-378798D01*
X218126Y-378772D01*
X218182Y-378746D01*
X218230Y-378720D01*
X218263Y-378695D01*
X218282Y-378680D01*
X218289Y-378672D01*
X218341Y-378613D01*
X218378Y-378554D01*
X218408Y-378491D01*
X218426Y-378435D01*
X218437Y-378384D01*
X218441Y-378347D01*
X218444Y-378332D01*
Y-378310D01*
X218437Y-378232D01*
X218419Y-378162D01*
X218396Y-378102D01*
X218367Y-378051D01*
X218337Y-378010D01*
X218315Y-377980D01*
X218297Y-377962D01*
X218289Y-377955D01*
X218226Y-377906D01*
X218160Y-377869D01*
X218089Y-377843D01*
X218023Y-377829D01*
X217964Y-377818D01*
X217938Y-377814D01*
X217916D01*
X217897Y-377810D01*
D02*
G37*
G36*
X219111Y-380152D02*
X217964D01*
Y-380959D01*
X219111Y-380152D01*
D02*
G37*
G36*
X222659Y-368349D02*
X221512D01*
Y-369156D01*
X222659Y-368349D01*
D02*
G37*
G36*
X237841Y-366113D02*
X237819D01*
X237815D01*
X237811D01*
X237752Y-366116D01*
X237697Y-366131D01*
X237649Y-366150D01*
X237608Y-366172D01*
X237575Y-366194D01*
X237552Y-366213D01*
X237534Y-366227D01*
X237530Y-366231D01*
X237493Y-366276D01*
X237464Y-366327D01*
X237445Y-366375D01*
X237430Y-366424D01*
X237423Y-366468D01*
X237419Y-366501D01*
X237416Y-366523D01*
Y-366531D01*
X237419Y-366597D01*
X237434Y-366657D01*
X237453Y-366708D01*
X237475Y-366753D01*
X237493Y-366786D01*
X237512Y-366812D01*
X237526Y-366830D01*
X237530Y-366834D01*
X237575Y-366871D01*
X237626Y-366901D01*
X237674Y-366919D01*
X237723Y-366934D01*
X237763Y-366941D01*
X237797Y-366945D01*
X237819Y-366949D01*
X237823D01*
X237826D01*
X237885Y-366945D01*
X237937Y-366930D01*
X237985Y-366912D01*
X238026Y-366890D01*
X238059Y-366871D01*
X238085Y-366853D01*
X238100Y-366838D01*
X238104Y-366834D01*
X238144Y-366786D01*
X238174Y-366738D01*
X238193Y-366686D01*
X238207Y-366638D01*
X238215Y-366594D01*
X238222Y-366560D01*
Y-366531D01*
X238218Y-366468D01*
X238204Y-366409D01*
X238185Y-366361D01*
X238163Y-366316D01*
X238141Y-366283D01*
X238122Y-366257D01*
X238107Y-366238D01*
X238104Y-366235D01*
X238056Y-366194D01*
X238007Y-366164D01*
X237959Y-366142D01*
X237915Y-366127D01*
X237874Y-366120D01*
X237841Y-366113D01*
D02*
G37*
G36*
X236657Y-366009D02*
X236646D01*
X236638D01*
X236635D01*
X236557Y-366017D01*
X236483Y-366031D01*
X236420Y-366057D01*
X236368Y-366083D01*
X236328Y-366109D01*
X236294Y-366135D01*
X236276Y-366150D01*
X236268Y-366157D01*
X236220Y-366216D01*
X236183Y-366276D01*
X236161Y-366338D01*
X236143Y-366398D01*
X236132Y-366449D01*
X236128Y-366494D01*
X236124Y-366509D01*
Y-366531D01*
X236128Y-366583D01*
X236135Y-366634D01*
X236146Y-366683D01*
X236157Y-366723D01*
X236169Y-366757D01*
X236180Y-366782D01*
X236187Y-366797D01*
X236191Y-366805D01*
X236220Y-366849D01*
X236250Y-366886D01*
X236283Y-366919D01*
X236317Y-366945D01*
X236343Y-366967D01*
X236365Y-366982D01*
X236383Y-366990D01*
X236387Y-366993D01*
X236435Y-367012D01*
X236479Y-367027D01*
X236524Y-367038D01*
X236564Y-367045D01*
X236598Y-367049D01*
X236624Y-367053D01*
X236638D01*
X236646D01*
X236724Y-367045D01*
X236794Y-367030D01*
X236857Y-367008D01*
X236912Y-366979D01*
X236953Y-366953D01*
X236986Y-366930D01*
X237005Y-366916D01*
X237012Y-366908D01*
X237060Y-366853D01*
X237097Y-366790D01*
X237123Y-366731D01*
X237142Y-366671D01*
X237153Y-366620D01*
X237157Y-366579D01*
X237160Y-366564D01*
Y-366542D01*
X237153Y-366460D01*
X237138Y-366387D01*
X237112Y-366320D01*
X237086Y-366264D01*
X237057Y-366220D01*
X237031Y-366187D01*
X237016Y-366168D01*
X237009Y-366161D01*
X236949Y-366109D01*
X236886Y-366072D01*
X236824Y-366046D01*
X236768Y-366028D01*
X236713Y-366017D01*
X236672Y-366013D01*
X236657Y-366009D01*
D02*
G37*
G36*
X237959Y-368355D02*
X236812D01*
Y-369162D01*
X237959Y-368355D01*
D02*
G37*
G36*
X241656Y-366035D02*
X241641D01*
X241634D01*
X241630D01*
X241534Y-366042D01*
X241449Y-366057D01*
X241378Y-366079D01*
X241319Y-366105D01*
X241271Y-366135D01*
X241238Y-366157D01*
X241216Y-366172D01*
X241208Y-366179D01*
X241157Y-366235D01*
X241120Y-366294D01*
X241094Y-366353D01*
X241075Y-366412D01*
X241064Y-366460D01*
X241060Y-366501D01*
X241057Y-366516D01*
Y-366538D01*
X241064Y-366616D01*
X241079Y-366686D01*
X241105Y-366749D01*
X241134Y-366805D01*
X241160Y-366845D01*
X241186Y-366879D01*
X241201Y-366897D01*
X241208Y-366904D01*
X241267Y-366953D01*
X241334Y-366990D01*
X241401Y-367012D01*
X241464Y-367030D01*
X241519Y-367041D01*
X241541Y-367045D01*
X241564D01*
X241582Y-367049D01*
X241593D01*
X241600D01*
X241604D01*
X241700Y-367041D01*
X241789Y-367027D01*
X241867Y-367001D01*
X241930Y-366971D01*
X241982Y-366945D01*
X242019Y-366919D01*
X242030Y-366912D01*
X242041Y-366904D01*
X242044Y-366897D01*
X242048D01*
X242078Y-366867D01*
X242107Y-366838D01*
X242148Y-366775D01*
X242181Y-366712D01*
X242200Y-366653D01*
X242215Y-366605D01*
X242218Y-366564D01*
X242222Y-366549D01*
Y-366490D01*
X242215Y-366453D01*
X242196Y-366387D01*
X242170Y-366327D01*
X242144Y-366276D01*
X242115Y-366235D01*
X242089Y-366205D01*
X242070Y-366187D01*
X242067Y-366179D01*
X242063D01*
X242000Y-366131D01*
X241930Y-366094D01*
X241856Y-366068D01*
X241786Y-366054D01*
X241726Y-366042D01*
X241700Y-366039D01*
X241674D01*
X241656Y-366035D01*
D02*
G37*
G36*
X241959Y-368355D02*
X240812D01*
Y-369162D01*
X241959Y-368355D01*
D02*
G37*
G36*
X252730Y-366003D02*
X252697D01*
X252679D01*
X252675D01*
X252671D01*
X252557D01*
X252453Y-366011D01*
X252361Y-366018D01*
X252272Y-366026D01*
X252198Y-366037D01*
X252127Y-366052D01*
X252068Y-366066D01*
X252013Y-366077D01*
X251968Y-366092D01*
X251931Y-366107D01*
X251898Y-366118D01*
X251872Y-366133D01*
X251854Y-366140D01*
X251842Y-366148D01*
X251835Y-366155D01*
X251831D01*
X251795Y-366185D01*
X251765Y-366214D01*
X251735Y-366244D01*
X251713Y-366274D01*
X251676Y-366336D01*
X251650Y-366392D01*
X251635Y-366444D01*
X251628Y-366481D01*
X251624Y-366496D01*
Y-366518D01*
X251628Y-366559D01*
X251632Y-366596D01*
X251658Y-366666D01*
X251691Y-366729D01*
X251728Y-366784D01*
X251765Y-366825D01*
X251798Y-366858D01*
X251824Y-366877D01*
X251828Y-366884D01*
X251831D01*
X251876Y-366910D01*
X251928Y-366932D01*
X251987Y-366954D01*
X252050Y-366969D01*
X252116Y-366984D01*
X252187Y-366995D01*
X252331Y-367014D01*
X252398Y-367021D01*
X252460Y-367025D01*
X252520Y-367028D01*
X252568D01*
X252612Y-367032D01*
X252645D01*
X252664D01*
X252671D01*
X252786Y-367028D01*
X252890Y-367025D01*
X252986Y-367017D01*
X253075Y-367006D01*
X253152Y-366995D01*
X253223Y-366980D01*
X253286Y-366966D01*
X253341Y-366951D01*
X253389Y-366936D01*
X253430Y-366925D01*
X253463Y-366910D01*
X253493Y-366899D01*
X253511Y-366888D01*
X253526Y-366880D01*
X253533Y-366873D01*
X253537D01*
X253570Y-366847D01*
X253600Y-366821D01*
X253622Y-366792D01*
X253644Y-366762D01*
X253678Y-366703D01*
X253700Y-366647D01*
X253711Y-366599D01*
X253718Y-366559D01*
X253722Y-366544D01*
Y-366522D01*
X253718Y-366481D01*
X253715Y-366440D01*
X253704Y-366403D01*
X253689Y-366370D01*
X253656Y-366307D01*
X253619Y-366251D01*
X253578Y-366211D01*
X253544Y-366177D01*
X253530Y-366166D01*
X253519Y-366159D01*
X253515Y-366151D01*
X253511D01*
X253467Y-366126D01*
X253415Y-366103D01*
X253356Y-366081D01*
X253293Y-366066D01*
X253226Y-366052D01*
X253156Y-366040D01*
X253015Y-366022D01*
X252945Y-366015D01*
X252882Y-366011D01*
X252823Y-366007D01*
X252775D01*
X252730Y-366003D01*
D02*
G37*
%LPD*%
D15*
X561877Y-282487D02*
G03*
X561877Y-282487I-394J0D01*
G01*
X540571Y-271732D02*
G03*
X540571Y-271732I-394J0D01*
G01*
X-20374Y-188583D02*
X-16437D01*
Y-175984D01*
X-20374D02*
X-16437D01*
X-20374Y-188583D02*
Y-175984D01*
Y-71457D02*
X-16437D01*
Y-58858D01*
X-20374D02*
X-16437D01*
X-20374Y-71457D02*
Y-58858D01*
Y-241339D02*
Y-228740D01*
X-16437D01*
Y-241339D02*
Y-228740D01*
X-20374Y-241339D02*
X-16437D01*
X-20374Y-294882D02*
Y-282283D01*
X-16437D01*
Y-294882D02*
Y-282283D01*
X-20374Y-294882D02*
X-16437D01*
X-20374Y-347638D02*
Y-335039D01*
X-16437D01*
Y-347638D02*
Y-335039D01*
X-20374Y-347638D02*
X-16437D01*
X-20374Y-114764D02*
Y-102165D01*
X-16437D01*
Y-114764D02*
Y-102165D01*
X-20374Y-114764D02*
X-16437D01*
D16*
X565420Y-283668D02*
Y-275400D01*
X570145D01*
Y-283668D02*
Y-275400D01*
X565420Y-283668D02*
X570145D01*
X536240Y-278819D02*
Y-270551D01*
X531516Y-278819D02*
X536240D01*
X531516D02*
Y-270551D01*
X536240D01*
D20*
X259602Y-121063D02*
X265310D01*
X259602Y-112402D02*
X265310D01*
X259602Y-121063D02*
Y-112402D01*
X265310Y-121063D02*
Y-112402D01*
X287303Y-275492D02*
Y-271752D01*
X293799Y-275492D02*
Y-271752D01*
X287303Y-275492D02*
X293799D01*
X287303Y-271752D02*
X293799D01*
X130512Y-349213D02*
Y-346850D01*
X134843Y-349213D02*
Y-346850D01*
X130512D02*
X134843D01*
X130512Y-349213D02*
X134843D01*
X130512Y-353543D02*
Y-351181D01*
X134843Y-353543D02*
Y-351181D01*
X130512D02*
X134843D01*
X130512Y-353543D02*
X134843D01*
X421303Y-360163D02*
X426618D01*
X421303Y-351502D02*
X426618D01*
Y-360163D02*
Y-351502D01*
X421303Y-360163D02*
Y-351502D01*
X466087Y-360950D02*
X471402D01*
X466087Y-352289D02*
X471402D01*
Y-360950D02*
Y-352289D01*
X466087Y-360950D02*
Y-352289D01*
X481047Y-359376D02*
Y-353864D01*
X489709Y-359376D02*
Y-353864D01*
X481047D02*
X489709D01*
X481047Y-359376D02*
X489709D01*
X436559Y-358588D02*
Y-353077D01*
X445221Y-358588D02*
Y-353077D01*
X436559D02*
X445221D01*
X436559Y-358588D02*
X445221D01*
X520945Y-359052D02*
Y-353540D01*
X529606Y-359052D02*
Y-353540D01*
X520945D02*
X529606D01*
X520945Y-359052D02*
X529606D01*
X565433Y-359446D02*
Y-353934D01*
X574094Y-359446D02*
Y-353934D01*
X565433D02*
X574094D01*
X565433Y-359446D02*
X574094D01*
X504508Y-360627D02*
X509823D01*
X504508Y-351966D02*
X509823D01*
Y-360627D02*
Y-351966D01*
X504508Y-360627D02*
Y-351966D01*
X549488Y-360430D02*
X554803D01*
X549488Y-351769D02*
X554803D01*
Y-360430D02*
Y-351769D01*
X549488Y-360430D02*
Y-351769D01*
X623721Y-43701D02*
Y-35039D01*
X618012Y-43701D02*
Y-35039D01*
X623721D01*
X618012Y-43701D02*
X623721D01*
X588681Y-34941D02*
X592421D01*
X588681Y-41437D02*
X592421D01*
Y-34941D01*
X588681Y-41437D02*
Y-34941D01*
X272260Y-382765D02*
X274622D01*
X272260Y-378435D02*
X274622D01*
Y-382765D02*
Y-378435D01*
X272260Y-382765D02*
Y-378435D01*
X205260Y-382765D02*
Y-378435D01*
X207622Y-382765D02*
Y-378435D01*
X205260D02*
X207622D01*
X205260Y-382765D02*
X207622D01*
X209260D02*
X211622D01*
X209260Y-378435D02*
X211622D01*
Y-382765D02*
Y-378435D01*
X209260Y-382765D02*
Y-378435D01*
X217160Y-382765D02*
Y-378435D01*
X219522Y-382765D02*
Y-378435D01*
X217160D02*
X219522D01*
X217160Y-382765D02*
X219522D01*
X221460D02*
X223822D01*
X221460Y-378435D02*
X223822D01*
Y-382765D02*
Y-378435D01*
X221460Y-382765D02*
Y-378435D01*
X236760Y-382765D02*
X239122D01*
X236760Y-378435D02*
X239122D01*
Y-382765D02*
Y-378435D01*
X236760Y-382765D02*
Y-378435D01*
X240760Y-382765D02*
X243122D01*
X240760Y-378435D02*
X243122D01*
Y-382765D02*
Y-378435D01*
X240760Y-382765D02*
Y-378435D01*
X252260Y-382765D02*
X254622D01*
X252260Y-378435D02*
X254622D01*
Y-382765D02*
Y-378435D01*
X252260Y-382765D02*
Y-378435D01*
X255760Y-382765D02*
Y-378435D01*
X258122Y-382765D02*
Y-378435D01*
X255760D02*
X258122D01*
X255760Y-382765D02*
X258122D01*
X268260D02*
X270622D01*
X268260Y-378435D02*
X270622D01*
Y-382765D02*
Y-378435D01*
X268260Y-382765D02*
Y-378435D01*
X472997Y-298335D02*
X476329Y-301667D01*
X472997D02*
X476329Y-298335D01*
X472997Y-300001D02*
X476329D01*
X474663Y-301667D02*
Y-298335D01*
X145437Y5996D02*
X148770Y2664D01*
X145437D02*
X148770Y5996D01*
X145437Y4330D02*
X148770D01*
X147104Y2664D02*
Y5996D01*
X556213Y-26364D02*
X552881Y-29696D01*
Y-26364D02*
X556213Y-29696D01*
X554547Y-26364D02*
Y-29696D01*
X552881Y-28030D02*
X556213D01*
X108522Y-5630D02*
X105190Y-8962D01*
Y-5630D02*
X108522Y-8962D01*
X106856Y-5630D02*
Y-8962D01*
X105190Y-7296D02*
X108522D01*
X430197Y-124008D02*
X426865Y-120676D01*
X430197D02*
X426865Y-124008D01*
X430197Y-122342D02*
X426865D01*
X428531Y-120676D02*
Y-124008D01*
D21*
X472247Y-310037D02*
Y-297837D01*
X484446D01*
Y-310037D02*
Y-297837D01*
X472247Y-310037D02*
X484446D01*
Y-301584D02*
Y-300384D01*
Y-301584D02*
Y-300384D01*
Y-303553D02*
Y-302353D01*
Y-303553D02*
Y-302353D01*
Y-305521D02*
Y-304321D01*
Y-305521D02*
Y-304321D01*
Y-307490D02*
Y-306290D01*
Y-307490D02*
Y-306290D01*
X480699Y-310037D02*
X481899D01*
X480699D02*
X481899D01*
X478731D02*
X479931D01*
X478731D02*
X479931D01*
X476762D02*
X477962D01*
X476762D02*
X477962D01*
X474794D02*
X475994D01*
X474794D02*
X475994D01*
X472247Y-307490D02*
Y-306290D01*
Y-307490D02*
Y-306290D01*
Y-305521D02*
Y-304321D01*
Y-305521D02*
Y-304321D01*
Y-303553D02*
Y-302353D01*
Y-303553D02*
Y-302353D01*
Y-301584D02*
Y-300384D01*
Y-301584D02*
Y-300384D01*
X474794Y-297837D02*
X475994D01*
X474794D02*
X475994D01*
X476762D02*
X477962D01*
X476762D02*
X477962D01*
X478731D02*
X479931D01*
X478731D02*
X479931D01*
X480699D02*
X481899D01*
X480699D02*
X481899D01*
X472247Y-302837D02*
X477247Y-297837D01*
X144687Y-5706D02*
Y6494D01*
X156887D01*
Y-5706D02*
Y6494D01*
X144687Y-5706D02*
X156887D01*
Y2747D02*
Y3946D01*
Y2747D02*
Y3946D01*
Y778D02*
Y1978D01*
Y778D02*
Y1978D01*
Y-1191D02*
Y9D01*
Y-1191D02*
Y9D01*
Y-3159D02*
Y-1959D01*
Y-3159D02*
Y-1959D01*
X153140Y-5706D02*
X154340D01*
X153140D02*
X154340D01*
X151172D02*
X152372D01*
X151172D02*
X152372D01*
X149203D02*
X150403D01*
X149203D02*
X150403D01*
X147235D02*
X148435D01*
X147235D02*
X148435D01*
X144687Y-3159D02*
Y-1959D01*
Y-3159D02*
Y-1959D01*
Y-1191D02*
Y9D01*
Y-1191D02*
Y9D01*
Y778D02*
Y1978D01*
Y778D02*
Y1978D01*
Y2747D02*
Y3946D01*
Y2747D02*
Y3946D01*
X147235Y6494D02*
X148435D01*
X147235D02*
X148435D01*
X149203D02*
X150403D01*
X149203D02*
X150403D01*
X151172D02*
X152372D01*
X151172D02*
X152372D01*
X153140D02*
X154340D01*
X153140D02*
X154340D01*
X144687Y1494D02*
X149687Y6494D01*
X553548Y-29364D02*
Y-25864D01*
X541948D02*
X553548D01*
X541948Y-29364D02*
Y-25864D01*
Y-29364D02*
X553548D01*
Y-47364D02*
Y-43864D01*
X541948D02*
X553548D01*
X541948Y-47364D02*
Y-43864D01*
Y-47364D02*
X553548D01*
Y-38364D02*
Y-34864D01*
X549548D02*
X553548D01*
X549548Y-38364D02*
Y-34864D01*
Y-38364D02*
X553548D01*
Y-49814D02*
Y-23414D01*
Y-49814D02*
X577948D01*
Y-23414D01*
X553548D02*
X577948D01*
X88757Y-1980D02*
X112357D01*
Y-25580D02*
Y-1980D01*
X88757Y-25580D02*
X112357D01*
X88757D02*
Y-1980D01*
X107507Y-25580D02*
Y-25179D01*
X106207D02*
X107507D01*
X106207Y-25580D02*
Y-25179D01*
Y-25580D02*
X107507D01*
X104357D02*
Y-25179D01*
X103057D02*
X104357D01*
X103057Y-25580D02*
Y-25179D01*
Y-25580D02*
X104357D01*
X101207D02*
Y-25179D01*
X99907D02*
X101207D01*
X99907Y-25580D02*
Y-25179D01*
Y-25580D02*
X101207D01*
X98058D02*
Y-25179D01*
X96758D02*
X98058D01*
X96758Y-25580D02*
Y-25179D01*
Y-25580D02*
X98058D01*
X94908D02*
Y-25179D01*
X93608D02*
X94908D01*
X93608Y-25580D02*
Y-25179D01*
Y-25580D02*
X94908D01*
X88757Y-20729D02*
X89157D01*
Y-19429D01*
X88757D02*
X89157D01*
X88757Y-20729D02*
Y-19429D01*
Y-17579D02*
X89157D01*
Y-16279D01*
X88757D02*
X89157D01*
X88757Y-17579D02*
Y-16279D01*
Y-14430D02*
X89157D01*
Y-13129D01*
X88757D02*
X89157D01*
X88757Y-14430D02*
Y-13129D01*
Y-11280D02*
X89157D01*
Y-9980D01*
X88757D02*
X89157D01*
X88757Y-11280D02*
Y-9980D01*
Y-8130D02*
X89157D01*
Y-6830D01*
X88757D02*
X89157D01*
X88757Y-8130D02*
Y-6830D01*
X93608Y-2379D02*
Y-1980D01*
Y-2379D02*
X94908D01*
Y-1980D01*
X93608D02*
X94908D01*
X96758Y-2379D02*
Y-1980D01*
Y-2379D02*
X98058D01*
Y-1980D01*
X96758D02*
X98058D01*
X99907Y-2379D02*
Y-1980D01*
Y-2379D02*
X101207D01*
Y-1980D01*
X99907D02*
X101207D01*
X103057Y-2379D02*
Y-1980D01*
Y-2379D02*
X104357D01*
Y-1980D01*
X103057D02*
X104357D01*
X106207Y-2379D02*
Y-1980D01*
Y-2379D02*
X107507D01*
Y-1980D01*
X106207D02*
X107507D01*
X111958Y-6830D02*
X112357D01*
X111958Y-8130D02*
Y-6830D01*
Y-8130D02*
X112357D01*
Y-6830D01*
X111958Y-9980D02*
X112357D01*
X111958Y-11280D02*
Y-9980D01*
Y-11280D02*
X112357D01*
Y-9980D01*
X111958Y-13129D02*
X112357D01*
X111958Y-14430D02*
Y-13129D01*
Y-14430D02*
X112357D01*
Y-13129D01*
X111958Y-16279D02*
X112357D01*
X111958Y-17579D02*
Y-16279D01*
Y-17579D02*
X112357D01*
Y-16279D01*
X111958Y-19429D02*
X112357D01*
X111958Y-20729D02*
Y-19429D01*
Y-20729D02*
X112357D01*
Y-19429D01*
X107358Y-1980D02*
X112357Y-6979D01*
X433847Y-127843D02*
Y-104243D01*
X410247Y-127843D02*
X433847D01*
X410247D02*
Y-104243D01*
X433847D01*
X410247Y-122993D02*
X410647D01*
Y-121693D01*
X410247D02*
X410647D01*
X410247Y-122993D02*
Y-121693D01*
Y-119843D02*
X410647D01*
Y-118543D01*
X410247D02*
X410647D01*
X410247Y-119843D02*
Y-118543D01*
Y-116693D02*
X410647D01*
Y-115393D01*
X410247D02*
X410647D01*
X410247Y-116693D02*
Y-115393D01*
Y-113544D02*
X410647D01*
Y-112244D01*
X410247D02*
X410647D01*
X410247Y-113544D02*
Y-112244D01*
Y-110394D02*
X410647D01*
Y-109094D01*
X410247D02*
X410647D01*
X410247Y-110394D02*
Y-109094D01*
X415098Y-104643D02*
Y-104243D01*
Y-104643D02*
X416398D01*
Y-104243D01*
X415098D02*
X416398D01*
X418248Y-104643D02*
Y-104243D01*
Y-104643D02*
X419548D01*
Y-104243D01*
X418248D02*
X419548D01*
X421397Y-104643D02*
Y-104243D01*
Y-104643D02*
X422697D01*
Y-104243D01*
X421397D02*
X422697D01*
X424547Y-104643D02*
Y-104243D01*
Y-104643D02*
X425847D01*
Y-104243D01*
X424547D02*
X425847D01*
X427697Y-104643D02*
Y-104243D01*
Y-104643D02*
X428997D01*
Y-104243D01*
X427697D02*
X428997D01*
X433447Y-109094D02*
X433847D01*
X433447Y-110394D02*
Y-109094D01*
Y-110394D02*
X433847D01*
Y-109094D01*
X433447Y-112244D02*
X433847D01*
X433447Y-113544D02*
Y-112244D01*
Y-113544D02*
X433847D01*
Y-112244D01*
X433447Y-115393D02*
X433847D01*
X433447Y-116693D02*
Y-115393D01*
Y-116693D02*
X433847D01*
Y-115393D01*
X433447Y-118543D02*
X433847D01*
X433447Y-119843D02*
Y-118543D01*
Y-119843D02*
X433847D01*
Y-118543D01*
X433447Y-121693D02*
X433847D01*
X433447Y-122993D02*
Y-121693D01*
Y-122993D02*
X433847D01*
Y-121693D01*
X428997Y-127843D02*
Y-127443D01*
X427697D02*
X428997D01*
X427697Y-127843D02*
Y-127443D01*
Y-127843D02*
X428997D01*
X425847D02*
Y-127443D01*
X424547D02*
X425847D01*
X424547Y-127843D02*
Y-127443D01*
Y-127843D02*
X425847D01*
X422697D02*
Y-127443D01*
X421397D02*
X422697D01*
X421397Y-127843D02*
Y-127443D01*
Y-127843D02*
X422697D01*
X419548D02*
Y-127443D01*
X418248D02*
X419548D01*
X418248Y-127843D02*
Y-127443D01*
Y-127843D02*
X419548D01*
X416398D02*
Y-127443D01*
X415098D02*
X416398D01*
X415098Y-127843D02*
Y-127443D01*
Y-127843D02*
X416398D01*
X428847D02*
X433847Y-122843D01*
D23*
X80651Y-117510D02*
G03*
X80651Y-117510I-1969J0D01*
G01*
X383957Y-240158D02*
G03*
X383957Y-240158I-1181J0D01*
G01*
X226378Y-127165D02*
G03*
X226378Y-127165I-1969J0D01*
G01*
X202362Y-126378D02*
G03*
X202362Y-126378I-1969J0D01*
G01*
X43334Y-155448D02*
Y-153283D01*
X47468Y-155448D02*
Y-153283D01*
X43334Y-155448D02*
X47468D01*
X43334Y-153283D02*
X47468D01*
X441535Y-155512D02*
Y-153150D01*
X445866Y-155512D02*
Y-153150D01*
X441535Y-155512D02*
X445866D01*
X441535Y-153150D02*
X445866D01*
X436122Y-143898D02*
X438484D01*
X436122Y-148228D02*
X438484D01*
X436122D02*
Y-143898D01*
X438484Y-148228D02*
Y-143898D01*
X440551Y-143898D02*
X442913D01*
X440551Y-148228D02*
X442913D01*
X440551D02*
Y-143898D01*
X442913Y-148228D02*
Y-143898D01*
X451673D02*
X454035D01*
X451673Y-148228D02*
X454035D01*
X451673D02*
Y-143898D01*
X454035Y-148228D02*
Y-143898D01*
X72244Y-394D02*
Y1969D01*
X67913Y-394D02*
Y1969D01*
X72244D01*
X67913Y-394D02*
X72244D01*
X52756Y-6890D02*
Y-4528D01*
X57087Y-6890D02*
Y-4528D01*
X52756Y-6890D02*
X57087D01*
X52756Y-4528D02*
X57087D01*
X532168Y-283563D02*
X536302D01*
X532168Y-281398D02*
X536302D01*
X532168Y-283563D02*
Y-281398D01*
X536302Y-283563D02*
Y-281398D01*
X564928Y-271759D02*
X569062D01*
X564928Y-273924D02*
X569062D01*
Y-271759D01*
X564928Y-273924D02*
Y-271759D01*
X541043Y-281988D02*
Y-277854D01*
X543209Y-281988D02*
Y-277854D01*
X541043D02*
X543209D01*
X541043Y-281988D02*
X543209D01*
X554692Y-274515D02*
X558826D01*
X554692Y-276680D02*
X558826D01*
Y-274515D01*
X554692Y-276680D02*
Y-274515D01*
X108563Y-31398D02*
X112697D01*
X108563Y-29232D02*
X112697D01*
X108563Y-31398D02*
Y-29232D01*
X112697Y-31398D02*
Y-29232D01*
X109941Y-21555D02*
X112106D01*
X109941Y-25689D02*
X112106D01*
X109941D02*
Y-21555D01*
X112106Y-25689D02*
Y-21555D01*
X75139Y-133652D02*
X94824D01*
X75139Y-113967D02*
X94824D01*
Y-133652D02*
Y-113967D01*
X75139Y-133652D02*
Y-113967D01*
X57914Y-135522D02*
Y-131781D01*
X64804Y-135522D02*
Y-131781D01*
X57914D02*
X64804D01*
X57914Y-135522D02*
X64804D01*
X47284Y-114459D02*
X51418D01*
X47284Y-116624D02*
X51418D01*
X47284D02*
Y-114459D01*
X51418Y-116624D02*
Y-114459D01*
X65887Y-127352D02*
Y-120266D01*
X61950Y-127352D02*
Y-120266D01*
X65887D01*
X61950Y-127352D02*
X65887D01*
X47284Y-112687D02*
X51418D01*
X47284Y-110522D02*
X51418D01*
Y-112687D02*
Y-110522D01*
X47284Y-112687D02*
Y-110522D01*
Y-109144D02*
X51418D01*
X47284Y-106978D02*
X51418D01*
Y-109144D02*
Y-106978D01*
X47284Y-109144D02*
Y-106978D01*
X127735Y-118115D02*
Y-114178D01*
X134822Y-118115D02*
Y-114178D01*
X127735D02*
X134822D01*
X127735Y-118115D02*
X134822D01*
X127672Y-112431D02*
Y-108494D01*
X134758Y-112431D02*
Y-108494D01*
X127672D02*
X134758D01*
X127672Y-112431D02*
X134758D01*
X293032Y-161260D02*
Y-109764D01*
Y-161260D02*
X303031D01*
Y-109764D01*
X293032D02*
X303031D01*
X316260Y-120669D02*
X326260D01*
X316260Y-160669D02*
X326260D01*
Y-120669D01*
X316260Y-160669D02*
Y-120669D01*
X251113Y-114277D02*
X255050D01*
X251113Y-121364D02*
X255050D01*
Y-114277D01*
X251113Y-121364D02*
Y-114277D01*
X263779Y-132480D02*
Y-125394D01*
X276772Y-132480D02*
Y-125394D01*
X263779D02*
X276772D01*
X263779Y-132480D02*
X276772D01*
X263779Y-144685D02*
X276772D01*
X263779Y-137598D02*
X276772D01*
Y-144685D02*
Y-137598D01*
X263779Y-144685D02*
Y-137598D01*
Y-156102D02*
X276772D01*
X263779Y-149016D02*
X276772D01*
Y-156102D02*
Y-149016D01*
X263779Y-156102D02*
Y-149016D01*
X161355Y-122539D02*
Y-120374D01*
X157221Y-122539D02*
Y-120374D01*
X161355D01*
X157221Y-122539D02*
X161355D01*
X378445Y-242421D02*
X394783D01*
X378445Y-226083D02*
X394783D01*
X378445Y-242421D02*
Y-226083D01*
X394783Y-242421D02*
Y-226083D01*
X630905Y-294783D02*
Y-265256D01*
X608858Y-294783D02*
Y-265256D01*
Y-294783D02*
X630905D01*
X608858Y-265256D02*
X630905D01*
X133366Y-8760D02*
X137500D01*
X133366Y-10925D02*
X137500D01*
X133366D02*
Y-8760D01*
X137500Y-10925D02*
Y-8760D01*
X581791Y-213091D02*
X585925D01*
X581791Y-215256D02*
X585925D01*
Y-213091D01*
X581791Y-215256D02*
Y-213091D01*
X582972Y-243898D02*
Y-239764D01*
X580807Y-243898D02*
Y-239764D01*
Y-243898D02*
X582972D01*
X580807Y-239764D02*
X582972D01*
X591043Y-186909D02*
Y-184744D01*
X586909Y-186909D02*
Y-184744D01*
X591043D01*
X586909Y-186909D02*
X591043D01*
X588681Y-179232D02*
X590846D01*
X588681Y-175098D02*
X590846D01*
Y-179232D02*
Y-175098D01*
X588681Y-179232D02*
Y-175098D01*
X588648Y-158154D02*
X590813D01*
X588648Y-162288D02*
X590813D01*
X588648D02*
Y-158154D01*
X590813Y-162288D02*
Y-158154D01*
X620680Y-181798D02*
Y-155998D01*
X594280D02*
X620680D01*
X594280Y-181798D02*
Y-155998D01*
Y-181798D02*
X620680D01*
X599311Y-145571D02*
Y-143405D01*
X595177Y-145571D02*
Y-143405D01*
Y-145571D02*
X599311D01*
X595177Y-143405D02*
X599311D01*
X536926Y-257185D02*
Y-254823D01*
X532595Y-257185D02*
Y-254823D01*
X536926D01*
X532595Y-257185D02*
X536926D01*
X535749Y-252067D02*
Y-249705D01*
X531418Y-252067D02*
Y-249705D01*
X535749D01*
X531418Y-252067D02*
X535749D01*
X533741Y-246555D02*
Y-244193D01*
X529410Y-246555D02*
Y-244193D01*
X533741D01*
X529410Y-246555D02*
X533741D01*
X209055Y-40923D02*
X211417D01*
X209055Y-36593D02*
X211417D01*
Y-40923D02*
Y-36593D01*
X209055Y-40923D02*
Y-36593D01*
X214173Y-38783D02*
X216535D01*
X214173Y-34452D02*
X216535D01*
Y-38783D02*
Y-34452D01*
X214173Y-38783D02*
Y-34452D01*
X219685Y-36464D02*
X222047D01*
X219685Y-32134D02*
X222047D01*
Y-36464D02*
Y-32134D01*
X219685Y-36464D02*
Y-32134D01*
X481595Y-275886D02*
X483760D01*
X481595Y-280020D02*
X483760D01*
Y-275886D01*
X481595Y-280020D02*
Y-275886D01*
X481988Y-257579D02*
X484154D01*
X481988Y-253445D02*
X484154D01*
X481988Y-257579D02*
Y-253445D01*
X484154Y-257579D02*
Y-253445D01*
X478839Y-280020D02*
X481004D01*
X478839Y-275886D02*
X481004D01*
X478839Y-280020D02*
Y-275886D01*
X481004Y-280020D02*
Y-275886D01*
X484744Y-280020D02*
X486909D01*
X484744Y-275886D02*
X486909D01*
X484744Y-280020D02*
Y-275886D01*
X486909Y-280020D02*
Y-275886D01*
X475689Y-253445D02*
X477854D01*
X475689Y-257579D02*
X477854D01*
Y-253445D01*
X475689Y-257579D02*
Y-253445D01*
X486319D02*
X488484D01*
X486319Y-257579D02*
X488484D01*
Y-253445D01*
X486319Y-257579D02*
Y-253445D01*
X492028Y-304626D02*
Y-302461D01*
X496161Y-304626D02*
Y-302461D01*
X492028D02*
X496161D01*
X492028Y-304626D02*
X496161D01*
X484547Y-318799D02*
Y-316634D01*
X488681Y-318799D02*
Y-316634D01*
X484547D02*
X488681D01*
X484547Y-318799D02*
X488681D01*
X460335Y-308169D02*
X462500D01*
X460335Y-312303D02*
X462500D01*
Y-308169D01*
X460335Y-312303D02*
Y-308169D01*
X475689Y-292224D02*
X477854D01*
X475689Y-288090D02*
X477854D01*
X475689Y-292224D02*
Y-288090D01*
X477854Y-292224D02*
Y-288090D01*
X482382Y-291831D02*
X484547D01*
X482382Y-287697D02*
X484547D01*
X482382Y-291831D02*
Y-287697D01*
X484547Y-291831D02*
Y-287697D01*
X489272Y-311319D02*
Y-309154D01*
X493405Y-311319D02*
Y-309154D01*
X489272D02*
X493405D01*
X489272Y-311319D02*
X493405D01*
X474114Y-316437D02*
Y-314272D01*
X469980Y-316437D02*
Y-314272D01*
Y-316437D02*
X474114D01*
X469980Y-314272D02*
X474114D01*
X465059Y-298524D02*
X467224D01*
X465059Y-294390D02*
X467224D01*
X465059Y-298524D02*
Y-294390D01*
X467224Y-298524D02*
Y-294390D01*
X464665Y-308169D02*
X466831D01*
X464665Y-312303D02*
X466831D01*
Y-308169D01*
X464665Y-312303D02*
Y-308169D01*
X489272Y-315256D02*
Y-313090D01*
X493405Y-315256D02*
Y-313090D01*
X489272D02*
X493405D01*
X489272Y-315256D02*
X493405D01*
X487500Y-295768D02*
X489665D01*
X487500Y-291634D02*
X489665D01*
X487500Y-295768D02*
Y-291634D01*
X489665Y-295768D02*
Y-291634D01*
X471752Y-292618D02*
X473917D01*
X471752Y-288484D02*
X473917D01*
X471752Y-292618D02*
Y-288484D01*
X473917Y-292618D02*
Y-288484D01*
X145768Y13681D02*
X147933D01*
X145768Y17815D02*
X147933D01*
X145768Y13681D02*
Y17815D01*
X147933Y13681D02*
Y17815D01*
X163484Y9350D02*
X165650D01*
X163484Y13484D02*
X165650D01*
X163484Y9350D02*
Y13484D01*
X165650Y9350D02*
Y13484D01*
X157579Y-9350D02*
X159744D01*
X157579Y-13484D02*
X159744D01*
Y-9350D01*
X157579Y-13484D02*
Y-9350D01*
X141437Y12894D02*
X143602D01*
X141437Y17028D02*
X143602D01*
X141437Y12894D02*
Y17028D01*
X143602Y12894D02*
Y17028D01*
X144980Y-12894D02*
Y-10728D01*
X140847Y-12894D02*
Y-10728D01*
Y-12894D02*
X144980D01*
X140847Y-10728D02*
X144980D01*
X161516Y-9350D02*
X163681D01*
X161516Y-13484D02*
X163681D01*
Y-9350D01*
X161516Y-13484D02*
Y-9350D01*
X158760Y9350D02*
X160925D01*
X158760Y13484D02*
X160925D01*
X158760Y9350D02*
Y13484D01*
X160925Y9350D02*
Y13484D01*
X150098Y14075D02*
X152264D01*
X150098Y18209D02*
X152264D01*
X150098Y14075D02*
Y18209D01*
X152264Y14075D02*
Y18209D01*
X137894Y-7382D02*
Y-5217D01*
X133760Y-7382D02*
Y-5217D01*
Y-7382D02*
X137894D01*
X133760Y-5217D02*
X137894D01*
X152461Y-10138D02*
X154626D01*
X152461Y-14272D02*
X154626D01*
Y-10138D01*
X152461Y-14272D02*
Y-10138D01*
X168209Y9350D02*
X170374D01*
X168209Y13484D02*
X170374D01*
X168209Y9350D02*
Y13484D01*
X170374Y9350D02*
Y13484D01*
X177067Y-88878D02*
Y-86713D01*
X181201Y-88878D02*
Y-86713D01*
X177067D02*
X181201D01*
X177067Y-88878D02*
X181201D01*
X177461Y-102264D02*
Y-100098D01*
X181595Y-102264D02*
Y-100098D01*
X177461D02*
X181595D01*
X177461Y-102264D02*
X181595D01*
X202067Y-88878D02*
Y-86713D01*
X197933Y-88878D02*
Y-86713D01*
Y-88878D02*
X202067D01*
X197933Y-86713D02*
X202067D01*
X200886Y-103839D02*
Y-101673D01*
X196752Y-103839D02*
Y-101673D01*
Y-103839D02*
X200886D01*
X196752Y-101673D02*
X200886D01*
X181201Y-93209D02*
Y-91043D01*
X177067Y-93209D02*
Y-91043D01*
Y-93209D02*
X181201D01*
X177067Y-91043D02*
X181201D01*
X197933Y-92815D02*
Y-90650D01*
X202067Y-92815D02*
Y-90650D01*
X197933D02*
X202067D01*
X197933Y-92815D02*
X202067D01*
X159744Y-53248D02*
X163878D01*
X159744Y-55413D02*
X163878D01*
X159744D02*
Y-53248D01*
X163878Y-55413D02*
Y-53248D01*
X541240Y-301870D02*
X545374D01*
X541240Y-299705D02*
X545374D01*
Y-301870D02*
Y-299705D01*
X541240Y-301870D02*
Y-299705D01*
X159744Y-57973D02*
X163878D01*
X159744Y-60138D02*
X163878D01*
X159744D02*
Y-57973D01*
X163878Y-60138D02*
Y-57973D01*
X548327Y-299705D02*
X552461D01*
X548327Y-301870D02*
X552461D01*
X548327D02*
Y-299705D01*
X552461Y-301870D02*
Y-299705D01*
X400295Y-131102D02*
X404626D01*
X400295Y-128740D02*
X404626D01*
X400295Y-131102D02*
Y-128740D01*
X404626Y-131102D02*
Y-128740D01*
X414233Y-105824D02*
X418563D01*
X414233Y-103462D02*
X418563D01*
X414233Y-105824D02*
Y-103462D01*
X418563Y-105824D02*
Y-103462D01*
X425689Y-106595D02*
Y-104429D01*
X421555Y-106595D02*
Y-104429D01*
X425689D01*
X421555Y-106595D02*
X425689D01*
X423622Y-139173D02*
X427953D01*
X423622Y-136811D02*
X427953D01*
X423622Y-139173D02*
Y-136811D01*
X427953Y-139173D02*
Y-136811D01*
X49016Y1575D02*
X53347D01*
X49016Y-787D02*
X53347D01*
Y1575D01*
X49016Y-787D02*
Y1575D01*
X56299Y-28543D02*
Y-26181D01*
X60630Y-28543D02*
Y-26181D01*
X56299Y-28543D02*
X60630D01*
X56299Y-26181D02*
X60630D01*
X61024Y-4528D02*
X65354D01*
X61024Y-6890D02*
X65354D01*
Y-4528D01*
X61024Y-6890D02*
Y-4528D01*
X93224Y-14212D02*
Y-12047D01*
X89091Y-14212D02*
Y-12047D01*
X93224D01*
X89091Y-14212D02*
X93224D01*
X88992Y-15748D02*
X93323D01*
X88992Y-18110D02*
X93323D01*
Y-15748D01*
X88992Y-18110D02*
Y-15748D01*
X377000Y-157579D02*
Y-153445D01*
X379165Y-157579D02*
Y-153445D01*
X377000D02*
X379165D01*
X377000Y-157579D02*
X379165D01*
X372000D02*
Y-153445D01*
X374165Y-157579D02*
Y-153445D01*
X372000D02*
X374165D01*
X372000Y-157579D02*
X374165D01*
X42776Y-49438D02*
Y-47273D01*
X46909Y-49438D02*
Y-47273D01*
X42776Y-49438D02*
X46909D01*
X42776Y-47273D02*
X46909D01*
X42776Y-44438D02*
Y-42273D01*
X46909Y-44438D02*
Y-42273D01*
X42776Y-44438D02*
X46909D01*
X42776Y-42273D02*
X46909D01*
X430367Y-205315D02*
Y-198622D01*
X434107Y-205315D02*
Y-198622D01*
X430367D02*
X434107D01*
X430367Y-205315D02*
X434107D01*
X423970Y-193701D02*
X427907D01*
X423970Y-200787D02*
X427907D01*
X423970D02*
Y-193701D01*
X427907Y-200787D02*
Y-193701D01*
X25295Y14469D02*
X32185D01*
X25295Y18209D02*
X32185D01*
X25295Y14469D02*
Y18209D01*
X32185Y14469D02*
Y18209D01*
X25295Y7579D02*
X32185D01*
X25295Y11319D02*
X32185D01*
X25295Y7579D02*
Y11319D01*
X32185Y7579D02*
Y11319D01*
X25295Y689D02*
X32185D01*
X25295Y4429D02*
X32185D01*
X25295Y689D02*
Y4429D01*
X32185Y689D02*
Y4429D01*
X25295Y-6201D02*
X32185D01*
X25295Y-2461D02*
X32185D01*
X25295Y-6201D02*
Y-2461D01*
X32185Y-6201D02*
Y-2461D01*
X589075Y-224016D02*
X591240D01*
X589075Y-228150D02*
X591240D01*
X589075D02*
Y-224016D01*
X591240Y-228150D02*
Y-224016D01*
X583366Y-197933D02*
Y-195768D01*
X587500Y-197933D02*
Y-195768D01*
X583366Y-197933D02*
X587500D01*
X583366Y-195768D02*
X587500D01*
X581791Y-205610D02*
X585925D01*
X581791Y-207776D02*
X585925D01*
Y-205610D01*
X581791Y-207776D02*
Y-205610D01*
X583563Y-228642D02*
X585728D01*
X583563Y-232776D02*
X585728D01*
X583563D02*
Y-228642D01*
X585728Y-232776D02*
Y-228642D01*
X400984Y-124508D02*
Y-117224D01*
X387402Y-124508D02*
Y-117224D01*
Y-124508D02*
X400984D01*
X387402Y-117224D02*
X400984D01*
X75492Y-43799D02*
Y-36516D01*
X89075Y-43799D02*
Y-36516D01*
X75492D02*
X89075D01*
X75492Y-43799D02*
X89075D01*
X382480Y-218898D02*
X386811D01*
X382480Y-216535D02*
X386811D01*
Y-218898D02*
Y-216535D01*
X382480Y-218898D02*
Y-216535D01*
X554724Y-342126D02*
Y-338189D01*
X561811Y-342126D02*
Y-338189D01*
X554724Y-342126D02*
X561811D01*
X554724Y-338189D02*
X561811D01*
X536614Y-340945D02*
Y-337008D01*
X529528Y-340945D02*
Y-337008D01*
X536614D01*
X529528Y-340945D02*
X536614D01*
X569685Y-321260D02*
Y-317323D01*
X562598Y-321260D02*
Y-317323D01*
X569685D01*
X562598Y-321260D02*
X569685D01*
X537008Y-302756D02*
Y-298819D01*
X529921Y-302756D02*
Y-298819D01*
X537008D01*
X529921Y-302756D02*
X537008D01*
X128947Y-67372D02*
Y-63435D01*
X121860Y-67372D02*
Y-63435D01*
X128947D01*
X121860Y-67372D02*
X128947D01*
X117037Y-49370D02*
Y-45433D01*
X124124Y-49370D02*
Y-45433D01*
X117037Y-49370D02*
X124124D01*
X117037Y-45433D02*
X124124D01*
X143307Y-78347D02*
X150394D01*
X143307Y-82284D02*
X150394D01*
Y-78347D01*
X143307Y-82284D02*
Y-78347D01*
X161024Y-49213D02*
Y-42126D01*
X164961Y-49213D02*
Y-42126D01*
X161024D02*
X164961D01*
X161024Y-49213D02*
X164961D01*
X608957Y-251673D02*
X613091D01*
X608957Y-253839D02*
X613091D01*
X608957D02*
Y-251673D01*
X613091Y-253839D02*
Y-251673D01*
X604783Y-244074D02*
Y-241909D01*
X600650Y-244074D02*
Y-241909D01*
X604783D01*
X600650Y-244074D02*
X604783D01*
X604783Y-240137D02*
Y-237972D01*
X600650Y-240137D02*
Y-237972D01*
X604783D01*
X600650Y-240137D02*
X604783D01*
X171758Y-124709D02*
X174120D01*
X171758Y-120379D02*
X174120D01*
Y-124709D02*
Y-120379D01*
X171758Y-124709D02*
Y-120379D01*
X57835Y-53808D02*
X60197D01*
X57835Y-58139D02*
X60197D01*
X57835D02*
Y-53808D01*
X60197Y-58139D02*
Y-53808D01*
X608858Y-61024D02*
Y-58661D01*
X613189Y-61024D02*
Y-58661D01*
X608858Y-61024D02*
X613189D01*
X608858Y-58661D02*
X613189D01*
X602274Y-83500D02*
X604439D01*
X602274Y-79366D02*
X604439D01*
Y-83500D02*
Y-79366D01*
X602274Y-83500D02*
Y-79366D01*
X597342Y-83563D02*
X599508D01*
X597342Y-79429D02*
X599508D01*
Y-83563D02*
Y-79429D01*
X597342Y-83563D02*
Y-79429D01*
X154465Y-136122D02*
X158599D01*
X154465Y-138287D02*
X158599D01*
Y-136122D01*
X154465Y-138287D02*
Y-136122D01*
X161945Y-135335D02*
X166079D01*
X161945Y-137500D02*
X166079D01*
Y-135335D01*
X161945Y-137500D02*
Y-135335D01*
X43209Y-149902D02*
Y-147736D01*
X47343Y-149902D02*
Y-147736D01*
X43209Y-149902D02*
X47343D01*
X43209Y-147736D02*
X47343D01*
X216535Y-136221D02*
X223622D01*
X216535Y-140157D02*
X223622D01*
Y-136221D01*
X216535Y-140157D02*
Y-136221D01*
X222244Y-130905D02*
X228937D01*
X222244Y-134449D02*
X228937D01*
Y-130905D01*
X222244Y-134449D02*
Y-130905D01*
X239173Y-133661D02*
Y-130118D01*
X232480Y-133661D02*
Y-130118D01*
X239173D01*
X232480Y-133661D02*
X239173D01*
X198819Y-113779D02*
Y-109843D01*
X191732Y-113779D02*
Y-109843D01*
X198819D01*
X191732Y-113779D02*
X198819D01*
X198327Y-132579D02*
Y-128839D01*
X204823Y-132579D02*
Y-128839D01*
X198327Y-132579D02*
X204823D01*
X198327Y-128839D02*
X204823D01*
X284941Y-207776D02*
Y-203642D01*
X282776Y-207776D02*
Y-203642D01*
X284941D01*
X282776Y-207776D02*
X284941D01*
X284744Y-187500D02*
Y-183366D01*
X286910Y-187500D02*
Y-183366D01*
X284744Y-187500D02*
X286910D01*
X284744Y-183366D02*
X286910D01*
X291240Y-195177D02*
X295374D01*
X291240Y-193012D02*
X295374D01*
Y-195177D02*
Y-193012D01*
X291240Y-195177D02*
Y-193012D01*
X289272Y-190847D02*
X293406D01*
X289272Y-188681D02*
X293406D01*
Y-190847D02*
Y-188681D01*
X289272Y-190847D02*
Y-188681D01*
X240551Y-130709D02*
Y-114961D01*
X220866Y-130709D02*
Y-114961D01*
X240551D01*
X220866Y-130709D02*
X240551D01*
X216535Y-129921D02*
Y-114173D01*
X196850Y-129921D02*
Y-114173D01*
X216535D01*
X196850Y-129921D02*
X216535D01*
X269193Y-191043D02*
X273327D01*
X269193Y-193209D02*
X273327D01*
X269193D02*
Y-191043D01*
X273327Y-193209D02*
Y-191043D01*
X280610Y-207972D02*
Y-203839D01*
X278445Y-207972D02*
Y-203839D01*
X280610D01*
X278445Y-207972D02*
X280610D01*
X269193Y-195374D02*
X273327D01*
X269193Y-197539D02*
X273327D01*
X269193D02*
Y-195374D01*
X273327Y-197539D02*
Y-195374D01*
X277264Y-187500D02*
Y-183366D01*
X279429Y-187500D02*
Y-183366D01*
X277264Y-187500D02*
X279429D01*
X277264Y-183366D02*
X279429D01*
X190292Y-131398D02*
Y-127264D01*
X188127Y-131398D02*
Y-127264D01*
X190292D01*
X188127Y-131398D02*
X190292D01*
X188127Y-117421D02*
X190292D01*
X188127Y-121555D02*
X190292D01*
Y-117421D01*
X188127Y-121555D02*
Y-117421D01*
X180843Y-133957D02*
Y-131791D01*
X184977Y-133957D02*
Y-131791D01*
X180843D02*
X184977D01*
X180843Y-133957D02*
X184977D01*
X180843Y-114665D02*
Y-112500D01*
X184977Y-114665D02*
Y-112500D01*
X180843D02*
X184977D01*
X180843Y-114665D02*
X184977D01*
X159091Y-119095D02*
Y-114961D01*
X156926Y-119095D02*
Y-114961D01*
Y-119095D02*
X159091D01*
X156926Y-114961D02*
X159091D01*
X384099Y-142520D02*
Y-140157D01*
X388429Y-142520D02*
Y-140157D01*
X384099Y-142520D02*
X388429D01*
X384099Y-140157D02*
X388429D01*
X161104Y-118679D02*
X165238D01*
X161104Y-116514D02*
X165238D01*
X161104Y-118679D02*
Y-116514D01*
X165238Y-118679D02*
Y-116514D01*
X165095Y-131791D02*
Y-127657D01*
X162930Y-131791D02*
Y-127657D01*
Y-131791D02*
X165095D01*
X162930Y-127657D02*
X165095D01*
X167260Y-114862D02*
X169623D01*
X167260Y-119193D02*
X169623D01*
X167260D02*
Y-114862D01*
X169623Y-119193D02*
Y-114862D01*
X155941Y-133268D02*
X160075D01*
X155941Y-131102D02*
X160075D01*
X155941Y-133268D02*
Y-131102D01*
X160075Y-133268D02*
Y-131102D01*
X157221Y-123917D02*
X161355D01*
X157221Y-126083D02*
X161355D01*
Y-123917D01*
X157221Y-126083D02*
Y-123917D01*
X160961Y-130020D02*
Y-127854D01*
X156827Y-130020D02*
Y-127854D01*
X160961D01*
X156827Y-130020D02*
X160961D01*
X16929Y-296654D02*
X19291D01*
X16929Y-292323D02*
X19291D01*
Y-296654D02*
Y-292323D01*
X16929Y-296654D02*
Y-292323D01*
X23031Y-296063D02*
Y-293701D01*
X27362Y-296063D02*
Y-293701D01*
X23031Y-296063D02*
X27362D01*
X23031Y-293701D02*
X27362D01*
X25095Y-215748D02*
Y-205512D01*
X14858D02*
X25095D01*
X14858Y-215748D02*
Y-205512D01*
Y-215748D02*
X25095D01*
X7480Y-193504D02*
X9843D01*
X7480Y-189173D02*
X9843D01*
Y-193504D02*
Y-189173D01*
X7480Y-193504D02*
Y-189173D01*
X-2362Y-349803D02*
X0D01*
X-2362Y-345472D02*
X0D01*
X-2362Y-349803D02*
Y-345472D01*
X0Y-349803D02*
Y-345472D01*
X18307Y-351181D02*
Y-348819D01*
X22638Y-351181D02*
Y-348819D01*
X18307D02*
X22638D01*
X18307Y-351181D02*
X22638D01*
X2953Y-235827D02*
Y-233465D01*
X7283Y-235827D02*
Y-233465D01*
X2953D02*
X7283D01*
X2953Y-235827D02*
X7283D01*
X23031Y-240551D02*
Y-238189D01*
X27362Y-240551D02*
Y-238189D01*
X23031D02*
X27362D01*
X23031Y-240551D02*
X27362D01*
X22638Y-193701D02*
Y-191339D01*
X26969Y-193701D02*
Y-191339D01*
X22638D02*
X26969D01*
X22638Y-193701D02*
X26969D01*
X312106Y-244390D02*
Y-242224D01*
X316240Y-244390D02*
Y-242224D01*
X312106D02*
X316240D01*
X312106Y-244390D02*
X316240D01*
X389764Y-248622D02*
X392126D01*
X389764Y-252953D02*
X392126D01*
Y-248622D01*
X389764Y-252953D02*
Y-248622D01*
X385433D02*
X387795D01*
X385433Y-252953D02*
X387795D01*
Y-248622D01*
X385433Y-252953D02*
Y-248622D01*
X400394D02*
X402756D01*
X400394Y-252953D02*
X402756D01*
Y-248622D01*
X400394Y-252953D02*
Y-248622D01*
X395669D02*
X398031D01*
X395669Y-252953D02*
X398031D01*
Y-248622D01*
X395669Y-252953D02*
Y-248622D01*
X405315Y-234252D02*
Y-231890D01*
X409646Y-234252D02*
Y-231890D01*
X405315D02*
X409646D01*
X405315Y-234252D02*
X409646D01*
X404921Y-239370D02*
Y-237008D01*
X409252Y-239370D02*
Y-237008D01*
X404921D02*
X409252D01*
X404921Y-239370D02*
X409252D01*
X404134Y-220866D02*
Y-218504D01*
X408465Y-220866D02*
Y-218504D01*
X404134D02*
X408465D01*
X404134Y-220866D02*
X408465D01*
X404134Y-225197D02*
Y-222835D01*
X408465Y-225197D02*
Y-222835D01*
X404134D02*
X408465D01*
X404134Y-225197D02*
X408465D01*
X381594Y-250098D02*
X383760D01*
X381594Y-245965D02*
X383760D01*
X381594Y-250098D02*
Y-245965D01*
X383760Y-250098D02*
Y-245965D01*
X375394Y-218898D02*
Y-216535D01*
X371063Y-218898D02*
Y-216535D01*
Y-218898D02*
X375394D01*
X371063Y-216535D02*
X375394D01*
X370374Y-237697D02*
Y-235531D01*
X374508Y-237697D02*
Y-235531D01*
X370374D02*
X374508D01*
X370374Y-237697D02*
X374508D01*
X370374Y-242421D02*
Y-240256D01*
X374508Y-242421D02*
Y-240256D01*
X370374D02*
X374508D01*
X370374Y-242421D02*
X374508D01*
X396949Y-220374D02*
Y-218209D01*
X392815Y-220374D02*
Y-218209D01*
Y-220374D02*
X396949D01*
X392815Y-218209D02*
X396949D01*
X602303Y-308307D02*
X622303D01*
Y-358307D02*
Y-308307D01*
X602303Y-358307D02*
X622303D01*
X602303D02*
Y-308307D01*
X338287Y-236910D02*
Y-234744D01*
X334154Y-236910D02*
Y-234744D01*
Y-236910D02*
X338287D01*
X334154Y-234744D02*
X338287D01*
X320374Y-251870D02*
Y-249705D01*
X324508Y-251870D02*
Y-249705D01*
X320374D02*
X324508D01*
X320374Y-251870D02*
X324508D01*
X320374Y-229823D02*
Y-227658D01*
X324508Y-229823D02*
Y-227658D01*
X320374D02*
X324508D01*
X320374Y-229823D02*
X324508D01*
X338681Y-243996D02*
Y-241831D01*
X334547Y-243996D02*
Y-241831D01*
Y-243996D02*
X338681D01*
X334547Y-241831D02*
X338681D01*
X314862Y-237303D02*
Y-235138D01*
X318996Y-237303D02*
Y-235138D01*
X314862D02*
X318996D01*
X314862Y-237303D02*
X318996D01*
X337303Y-282185D02*
Y-280020D01*
X341437Y-282185D02*
Y-280020D01*
X337303D02*
X341437D01*
X337303Y-282185D02*
X341437D01*
X337697Y-304232D02*
Y-302067D01*
X341831Y-304232D02*
Y-302067D01*
X337697D02*
X341831D01*
X337697Y-304232D02*
X341831D01*
X318012Y-284547D02*
Y-282382D01*
X322146Y-284547D02*
Y-282382D01*
X318012D02*
X322146D01*
X318012Y-284547D02*
X322146D01*
X317618Y-304626D02*
Y-302461D01*
X321752Y-304626D02*
Y-302461D01*
X317618D02*
X321752D01*
X317618Y-304626D02*
X321752D01*
X600394Y-240059D02*
Y-237894D01*
X604528Y-240059D02*
Y-237894D01*
X600394D02*
X604528D01*
X600394Y-240059D02*
X604528D01*
X352658Y-289665D02*
Y-287500D01*
X348524Y-289665D02*
Y-287500D01*
Y-289665D02*
X352658D01*
X348524Y-287500D02*
X352658D01*
X331988Y-282185D02*
X334154D01*
X331988Y-286319D02*
X334154D01*
Y-282185D01*
X331988Y-286319D02*
Y-282185D01*
X351870Y-297146D02*
Y-294980D01*
X347736Y-297146D02*
Y-294980D01*
Y-297146D02*
X351870D01*
X347736Y-294980D02*
X351870D01*
X331988Y-302854D02*
X334154D01*
X331988Y-298721D02*
X334154D01*
X331988Y-302854D02*
Y-298721D01*
X334154Y-302854D02*
Y-298721D01*
X326870Y-282185D02*
X329035D01*
X326870Y-286319D02*
X329035D01*
Y-282185D01*
X326870Y-286319D02*
Y-282185D01*
X307776Y-290453D02*
Y-288287D01*
X311910Y-290453D02*
Y-288287D01*
X307776D02*
X311910D01*
X307776Y-290453D02*
X311910D01*
X327658Y-302658D02*
X329823D01*
X327658Y-298524D02*
X329823D01*
X327658Y-302658D02*
Y-298524D01*
X329823Y-302658D02*
Y-298524D01*
X306988Y-297539D02*
Y-295374D01*
X311122Y-297539D02*
Y-295374D01*
X306988D02*
X311122D01*
X306988Y-297539D02*
X311122D01*
X600394Y-243996D02*
Y-241831D01*
X604528Y-243996D02*
Y-241831D01*
X600394D02*
X604528D01*
X600394Y-243996D02*
X604528D01*
X614272Y-229823D02*
Y-227658D01*
X610138Y-229823D02*
Y-227658D01*
Y-229823D02*
X614272D01*
X610138Y-227658D02*
X614272D01*
X620374Y-229429D02*
Y-227264D01*
X624508Y-229429D02*
Y-227264D01*
X620374D02*
X624508D01*
X620374Y-229429D02*
X624508D01*
X588189Y-56004D02*
Y-48720D01*
X601772Y-56004D02*
Y-48720D01*
X588189D02*
X601772D01*
X588189Y-56004D02*
X601772D01*
X609842Y-37402D02*
X613779D01*
X609842Y-44488D02*
X613779D01*
Y-37402D01*
X609842Y-44488D02*
Y-37402D01*
X595669Y-27756D02*
X602756D01*
X595669Y-40748D02*
X602756D01*
Y-27756D01*
X595669Y-40748D02*
Y-27756D01*
X5315Y-330561D02*
Y-303002D01*
X-22244D02*
X5315D01*
X-22244Y-330561D02*
X5315D01*
X-22244D02*
Y-303002D01*
X5315Y-277410D02*
Y-249850D01*
X-22244D02*
X5315D01*
X-22244Y-277410D02*
X5315D01*
X-22244D02*
Y-249850D01*
X5315Y-224260D02*
Y-196701D01*
X-22244D02*
X5315D01*
X-22244Y-224260D02*
X5315D01*
X-22244D02*
Y-196701D01*
X5315Y-171112D02*
Y-143553D01*
X-22244D02*
X5315D01*
X-22244Y-171112D02*
X5315D01*
X-22244D02*
Y-143553D01*
X16339Y-235827D02*
X25394D01*
X16339D02*
Y-227953D01*
X25394D01*
Y-235827D02*
Y-227953D01*
X23425Y-235827D02*
X25394Y-233858D01*
X16339Y-188189D02*
X25394D01*
X16339D02*
Y-180315D01*
X25394D01*
Y-188189D02*
Y-180315D01*
X23425Y-188189D02*
X25394Y-186221D01*
X16339Y-292913D02*
X25394D01*
X16339D02*
Y-285039D01*
X25394D01*
Y-292913D02*
Y-285039D01*
X23425Y-292913D02*
X25394Y-290945D01*
X14858Y-267913D02*
X25095D01*
X14858D02*
Y-257677D01*
X25095D01*
Y-267913D02*
Y-257677D01*
X14858Y-162450D02*
X25095D01*
X14858D02*
Y-152214D01*
X25095D01*
Y-162450D02*
Y-152214D01*
X11220Y-345669D02*
X20276D01*
X11220D02*
Y-337795D01*
X20276D01*
Y-345669D02*
Y-337795D01*
X18307Y-345669D02*
X20276Y-343701D01*
X14858Y-322047D02*
X25095D01*
X14858D02*
Y-311811D01*
X25095D01*
Y-322047D02*
Y-311811D01*
X-591Y-341535D02*
X2953D01*
X-591Y-334842D02*
X2953D01*
X-591Y-341535D02*
Y-334842D01*
X2953Y-341535D02*
Y-334842D01*
X9646Y-226575D02*
X13189D01*
X9646Y-219882D02*
X13189D01*
X9646Y-226575D02*
Y-219882D01*
X13189Y-226575D02*
Y-219882D01*
X15157Y-282480D02*
Y-278937D01*
X8465Y-282480D02*
Y-278937D01*
Y-282480D02*
X15157D01*
X8465Y-278937D02*
X15157D01*
X9646Y-173819D02*
X16339D01*
X9646Y-177362D02*
X16339D01*
X9646D02*
Y-173819D01*
X16339Y-177362D02*
Y-173819D01*
M02*
